FILE_TYPE = MACRO_DRAWING;
SET COLOR_WIRE YELLOW;
SET COLOR_PROP MONO;
SET COLOR_DOT WHITE;
SET COLOR_ARC YELLOW;
SET COLOR_BODY GREEN;
SET COLOR_NOTE MONO;
SET PROP_DISPLAY VALUE;
SET PAGE_NUMBER P49;
FORCEADD OFFPAGE..3
(1650 5250);
FORCEPROP 2 LAST $XR1 50 
J 0
(1954 5250);
DISPLAY 0.638298 (1954 5250);
PAINT MONO (1954 5250);
FORCEPROP 2 LAST $XR0 26 
J 0
(1864 5250);
DISPLAY 0.638298 (1864 5250);
PAINT MONO (1864 5250);
FORCEPROP 2 LAST CDS_LIB mstr_standard
J 0
(1650 5250);
DISPLAY 0.787234 (1650 5250);
PAINT MONO (1650 5250);
DISPLAY INVISIBLE (1650 5250);
FORCEPROP 1 LAST OFFPAGE TRUE
J 0
(1975 5125);
DISPLAY 0.936170 (1975 5125);
PAINT GREEN (1975 5125);
DISPLAY INVISIBLE (1975 5125);
FORCEPROP 1 LAST COMMENT_BODY TRUE
J 0
(1600 5150);
DISPLAY 0.936170 (1600 5150);
PAINT GREEN (1600 5150);
DISPLAY INVISIBLE (1600 5150);
FORCEPROP 2 LAST PATH I1
J 0
(1850 5325);
DISPLAY 0.787234 (1850 5325);
PAINT MONO (1850 5325);
DISPLAY INVISIBLE (1850 5325);
FORCEADD TAP..6
R 2
(650 5100);
FORCEPROP 3 LASTPIN (600 5100) SIG_NAME M_D_DQS_DP<16>
J 0
(610 5110);
DISPLAY 0.659574 (610 5110);
PAINT MONO (610 5110);
DISPLAY INVISIBLE (610 5110);
FORCEPROP 1 LASTPIN (600 5100) BN 16
J 2
(650 5110);
DISPLAY 0.617021 (650 5110);
PAINT PINK (650 5110);
FORCEPROP 2 LAST CDS_LIB mstr_standard
J 0
(650 5100);
DISPLAY 0.787234 (650 5100);
PAINT MONO (650 5100);
DISPLAY INVISIBLE (650 5100);
FORCEPROP 1 LAST BODY_TYPE PLUMBING
J 2
(650 5050);
DISPLAY 1.234043 (650 5050);
PAINT GREEN (650 5050);
DISPLAY INVISIBLE (650 5050);
FORCEPROP 1 LAST HDL_TAP TRUE
J 2
(325 4975);
DISPLAY 1.234043 (325 4975);
PAINT GREEN (325 4975);
DISPLAY INVISIBLE (325 4975);
FORCEPROP 1 LAST PATH I10
J 2
(650 5100);
DISPLAY 0.936170 (650 5100);
PAINT GREEN (650 5100);
DISPLAY INVISIBLE (650 5100);
FORCEADD TAP..6
R 2
(-1750 2500);
FORCEPROP 3 LASTPIN (-1800 2500) SIG_NAME M_D_DQ<11>
J 0
(-1790 2510);
DISPLAY 0.659574 (-1790 2510);
PAINT MONO (-1790 2510);
DISPLAY INVISIBLE (-1790 2510);
FORCEPROP 1 LASTPIN (-1800 2500) BN 11
J 2
(-1750 2510);
DISPLAY 0.617021 (-1750 2510);
PAINT PINK (-1750 2510);
FORCEPROP 2 LAST CDS_LIB mstr_standard
J 2
(-1750 2500);
DISPLAY 0.787234 (-1750 2500);
PAINT MONO (-1750 2500);
DISPLAY INVISIBLE (-1750 2500);
FORCEPROP 1 LAST BODY_TYPE PLUMBING
J 2
(-1750 2450);
DISPLAY 1.234043 (-1750 2450);
PAINT GREEN (-1750 2450);
DISPLAY INVISIBLE (-1750 2450);
FORCEPROP 1 LAST HDL_TAP TRUE
J 2
(-2075 2375);
DISPLAY 1.234043 (-2075 2375);
PAINT GREEN (-2075 2375);
DISPLAY INVISIBLE (-2075 2375);
FORCEPROP 1 LAST PATH I100
J 2
(-1750 2500);
DISPLAY 0.936170 (-1750 2500);
PAINT GREEN (-1750 2500);
DISPLAY INVISIBLE (-1750 2500);
FORCEADD TAP..6
R 2
(-1750 2450);
FORCEPROP 3 LASTPIN (-1800 2450) SIG_NAME M_D_DQ<8>
J 0
(-1790 2460);
DISPLAY 0.659574 (-1790 2460);
PAINT MONO (-1790 2460);
DISPLAY INVISIBLE (-1790 2460);
FORCEPROP 1 LASTPIN (-1800 2450) BN 8
J 2
(-1750 2460);
DISPLAY 0.617021 (-1750 2460);
PAINT PINK (-1750 2460);
FORCEPROP 2 LAST CDS_LIB mstr_standard
J 2
(-1750 2450);
DISPLAY 0.787234 (-1750 2450);
PAINT MONO (-1750 2450);
DISPLAY INVISIBLE (-1750 2450);
FORCEPROP 1 LAST BODY_TYPE PLUMBING
J 2
(-1750 2400);
DISPLAY 1.234043 (-1750 2400);
PAINT GREEN (-1750 2400);
DISPLAY INVISIBLE (-1750 2400);
FORCEPROP 1 LAST HDL_TAP TRUE
J 2
(-2075 2325);
DISPLAY 1.234043 (-2075 2325);
PAINT GREEN (-2075 2325);
DISPLAY INVISIBLE (-2075 2325);
FORCEPROP 1 LAST PATH I101
J 2
(-1750 2450);
DISPLAY 0.936170 (-1750 2450);
PAINT GREEN (-1750 2450);
DISPLAY INVISIBLE (-1750 2450);
FORCEADD TAP..6
R 2
(-1750 2350);
FORCEPROP 3 LASTPIN (-1800 2350) SIG_NAME M_D_DQ<6>
J 0
(-1790 2360);
DISPLAY 0.659574 (-1790 2360);
PAINT MONO (-1790 2360);
DISPLAY INVISIBLE (-1790 2360);
FORCEPROP 1 LASTPIN (-1800 2350) BN 6
J 2
(-1750 2360);
DISPLAY 0.617021 (-1750 2360);
PAINT PINK (-1750 2360);
FORCEPROP 2 LAST CDS_LIB mstr_standard
J 2
(-1750 2350);
DISPLAY 0.787234 (-1750 2350);
PAINT MONO (-1750 2350);
DISPLAY INVISIBLE (-1750 2350);
FORCEPROP 1 LAST BODY_TYPE PLUMBING
J 2
(-1750 2300);
DISPLAY 1.234043 (-1750 2300);
PAINT GREEN (-1750 2300);
DISPLAY INVISIBLE (-1750 2300);
FORCEPROP 1 LAST HDL_TAP TRUE
J 2
(-2075 2225);
DISPLAY 1.234043 (-2075 2225);
PAINT GREEN (-2075 2225);
DISPLAY INVISIBLE (-2075 2225);
FORCEPROP 1 LAST PATH I102
J 2
(-1750 2350);
DISPLAY 0.936170 (-1750 2350);
PAINT GREEN (-1750 2350);
DISPLAY INVISIBLE (-1750 2350);
FORCEADD TAP..6
R 2
(-1750 2400);
FORCEPROP 3 LASTPIN (-1800 2400) SIG_NAME M_D_DQ<9>
J 0
(-1790 2410);
DISPLAY 0.659574 (-1790 2410);
PAINT MONO (-1790 2410);
DISPLAY INVISIBLE (-1790 2410);
FORCEPROP 1 LASTPIN (-1800 2400) BN 9
J 2
(-1750 2410);
DISPLAY 0.617021 (-1750 2410);
PAINT PINK (-1750 2410);
FORCEPROP 2 LAST CDS_LIB mstr_standard
J 2
(-1750 2400);
DISPLAY 0.787234 (-1750 2400);
PAINT MONO (-1750 2400);
DISPLAY INVISIBLE (-1750 2400);
FORCEPROP 1 LAST BODY_TYPE PLUMBING
J 2
(-1750 2350);
DISPLAY 1.234043 (-1750 2350);
PAINT GREEN (-1750 2350);
DISPLAY INVISIBLE (-1750 2350);
FORCEPROP 1 LAST HDL_TAP TRUE
J 2
(-2075 2275);
DISPLAY 1.234043 (-2075 2275);
PAINT GREEN (-2075 2275);
DISPLAY INVISIBLE (-2075 2275);
FORCEPROP 1 LAST PATH I103
J 2
(-1750 2400);
DISPLAY 0.936170 (-1750 2400);
PAINT GREEN (-1750 2400);
DISPLAY INVISIBLE (-1750 2400);
FORCEADD TAP..6
R 2
(-1750 2300);
FORCEPROP 3 LASTPIN (-1800 2300) SIG_NAME M_D_DQ<7>
J 0
(-1790 2310);
DISPLAY 0.659574 (-1790 2310);
PAINT MONO (-1790 2310);
DISPLAY INVISIBLE (-1790 2310);
FORCEPROP 1 LASTPIN (-1800 2300) BN 7
J 2
(-1750 2310);
DISPLAY 0.617021 (-1750 2310);
PAINT PINK (-1750 2310);
FORCEPROP 2 LAST CDS_LIB mstr_standard
J 2
(-1750 2300);
DISPLAY 0.787234 (-1750 2300);
PAINT MONO (-1750 2300);
DISPLAY INVISIBLE (-1750 2300);
FORCEPROP 1 LAST BODY_TYPE PLUMBING
J 2
(-1750 2250);
DISPLAY 1.234043 (-1750 2250);
PAINT GREEN (-1750 2250);
DISPLAY INVISIBLE (-1750 2250);
FORCEPROP 1 LAST HDL_TAP TRUE
J 2
(-2075 2175);
DISPLAY 1.234043 (-2075 2175);
PAINT GREEN (-2075 2175);
DISPLAY INVISIBLE (-2075 2175);
FORCEPROP 1 LAST PATH I104
J 2
(-1750 2300);
DISPLAY 0.936170 (-1750 2300);
PAINT GREEN (-1750 2300);
DISPLAY INVISIBLE (-1750 2300);
FORCEADD TAP..6
R 2
(-1750 2250);
FORCEPROP 3 LASTPIN (-1800 2250) SIG_NAME M_D_DQ<4>
J 0
(-1790 2260);
DISPLAY 0.659574 (-1790 2260);
PAINT MONO (-1790 2260);
DISPLAY INVISIBLE (-1790 2260);
FORCEPROP 1 LASTPIN (-1800 2250) BN 4
J 2
(-1750 2260);
DISPLAY 0.617021 (-1750 2260);
PAINT PINK (-1750 2260);
FORCEPROP 2 LAST CDS_LIB mstr_standard
J 2
(-1750 2250);
DISPLAY 0.787234 (-1750 2250);
PAINT MONO (-1750 2250);
DISPLAY INVISIBLE (-1750 2250);
FORCEPROP 1 LAST BODY_TYPE PLUMBING
J 2
(-1750 2200);
DISPLAY 1.234043 (-1750 2200);
PAINT GREEN (-1750 2200);
DISPLAY INVISIBLE (-1750 2200);
FORCEPROP 1 LAST HDL_TAP TRUE
J 2
(-2075 2125);
DISPLAY 1.234043 (-2075 2125);
PAINT GREEN (-2075 2125);
DISPLAY INVISIBLE (-2075 2125);
FORCEPROP 1 LAST PATH I105
J 2
(-1750 2250);
DISPLAY 0.936170 (-1750 2250);
PAINT GREEN (-1750 2250);
DISPLAY INVISIBLE (-1750 2250);
FORCEADD TAP..6
R 2
(-1750 2150);
FORCEPROP 3 LASTPIN (-1800 2150) SIG_NAME M_D_DQ<2>
J 0
(-1790 2160);
DISPLAY 0.659574 (-1790 2160);
PAINT MONO (-1790 2160);
DISPLAY INVISIBLE (-1790 2160);
FORCEPROP 1 LASTPIN (-1800 2150) BN 2
J 2
(-1750 2160);
DISPLAY 0.617021 (-1750 2160);
PAINT PINK (-1750 2160);
FORCEPROP 2 LAST CDS_LIB mstr_standard
J 2
(-1750 2150);
DISPLAY 0.787234 (-1750 2150);
PAINT MONO (-1750 2150);
DISPLAY INVISIBLE (-1750 2150);
FORCEPROP 1 LAST BODY_TYPE PLUMBING
J 2
(-1750 2100);
DISPLAY 1.234043 (-1750 2100);
PAINT GREEN (-1750 2100);
DISPLAY INVISIBLE (-1750 2100);
FORCEPROP 1 LAST HDL_TAP TRUE
J 2
(-2075 2025);
DISPLAY 1.234043 (-2075 2025);
PAINT GREEN (-2075 2025);
DISPLAY INVISIBLE (-2075 2025);
FORCEPROP 1 LAST PATH I106
J 2
(-1750 2150);
DISPLAY 0.936170 (-1750 2150);
PAINT GREEN (-1750 2150);
DISPLAY INVISIBLE (-1750 2150);
FORCEADD TAP..6
R 2
(-1750 2200);
FORCEPROP 3 LASTPIN (-1800 2200) SIG_NAME M_D_DQ<5>
J 0
(-1790 2210);
DISPLAY 0.659574 (-1790 2210);
PAINT MONO (-1790 2210);
DISPLAY INVISIBLE (-1790 2210);
FORCEPROP 1 LASTPIN (-1800 2200) BN 5
J 2
(-1750 2210);
DISPLAY 0.617021 (-1750 2210);
PAINT PINK (-1750 2210);
FORCEPROP 2 LAST CDS_LIB mstr_standard
J 2
(-1750 2200);
DISPLAY 0.787234 (-1750 2200);
PAINT MONO (-1750 2200);
DISPLAY INVISIBLE (-1750 2200);
FORCEPROP 1 LAST BODY_TYPE PLUMBING
J 2
(-1750 2150);
DISPLAY 1.234043 (-1750 2150);
PAINT GREEN (-1750 2150);
DISPLAY INVISIBLE (-1750 2150);
FORCEPROP 1 LAST HDL_TAP TRUE
J 2
(-2075 2075);
DISPLAY 1.234043 (-2075 2075);
PAINT GREEN (-2075 2075);
DISPLAY INVISIBLE (-2075 2075);
FORCEPROP 1 LAST PATH I107
J 2
(-1750 2200);
DISPLAY 0.936170 (-1750 2200);
PAINT GREEN (-1750 2200);
DISPLAY INVISIBLE (-1750 2200);
FORCEADD TAP..6
R 2
(-1750 2050);
FORCEPROP 3 LASTPIN (-1800 2050) SIG_NAME M_D_DQ<0>
J 0
(-1790 2060);
DISPLAY 0.659574 (-1790 2060);
PAINT MONO (-1790 2060);
DISPLAY INVISIBLE (-1790 2060);
FORCEPROP 1 LASTPIN (-1800 2050) BN 0
J 2
(-1750 2060);
DISPLAY 0.617021 (-1750 2060);
PAINT PINK (-1750 2060);
FORCEPROP 2 LAST CDS_LIB mstr_standard
J 2
(-1750 2050);
DISPLAY 0.787234 (-1750 2050);
PAINT MONO (-1750 2050);
DISPLAY INVISIBLE (-1750 2050);
FORCEPROP 1 LAST BODY_TYPE PLUMBING
J 2
(-1750 2000);
DISPLAY 1.234043 (-1750 2000);
PAINT GREEN (-1750 2000);
DISPLAY INVISIBLE (-1750 2000);
FORCEPROP 1 LAST HDL_TAP TRUE
J 2
(-2075 1925);
DISPLAY 1.234043 (-2075 1925);
PAINT GREEN (-2075 1925);
DISPLAY INVISIBLE (-2075 1925);
FORCEPROP 1 LAST PATH I108
J 2
(-1750 2050);
DISPLAY 0.936170 (-1750 2050);
PAINT GREEN (-1750 2050);
DISPLAY INVISIBLE (-1750 2050);
FORCEADD TAP..6
R 2
(-1750 2100);
FORCEPROP 3 LASTPIN (-1800 2100) SIG_NAME M_D_DQ<3>
J 0
(-1790 2110);
DISPLAY 0.659574 (-1790 2110);
PAINT MONO (-1790 2110);
DISPLAY INVISIBLE (-1790 2110);
FORCEPROP 1 LASTPIN (-1800 2100) BN 3
J 2
(-1750 2110);
DISPLAY 0.617021 (-1750 2110);
PAINT PINK (-1750 2110);
FORCEPROP 2 LAST CDS_LIB mstr_standard
J 2
(-1750 2100);
DISPLAY 0.787234 (-1750 2100);
PAINT MONO (-1750 2100);
DISPLAY INVISIBLE (-1750 2100);
FORCEPROP 1 LAST BODY_TYPE PLUMBING
J 2
(-1750 2050);
DISPLAY 1.234043 (-1750 2050);
PAINT GREEN (-1750 2050);
DISPLAY INVISIBLE (-1750 2050);
FORCEPROP 1 LAST HDL_TAP TRUE
J 2
(-2075 1975);
DISPLAY 1.234043 (-2075 1975);
PAINT GREEN (-2075 1975);
DISPLAY INVISIBLE (-2075 1975);
FORCEPROP 1 LAST PATH I109
J 2
(-1750 2100);
DISPLAY 0.936170 (-1750 2100);
PAINT GREEN (-1750 2100);
DISPLAY INVISIBLE (-1750 2100);
FORCEADD TAP..6
R 2
(650 5000);
FORCEPROP 3 LASTPIN (600 5000) SIG_NAME M_D_DQS_DP<15>
J 0
(610 5010);
DISPLAY 0.659574 (610 5010);
PAINT MONO (610 5010);
DISPLAY INVISIBLE (610 5010);
FORCEPROP 1 LASTPIN (600 5000) BN 15
J 2
(650 5010);
DISPLAY 0.617021 (650 5010);
PAINT PINK (650 5010);
FORCEPROP 2 LAST CDS_LIB mstr_standard
J 0
(650 5000);
DISPLAY 0.787234 (650 5000);
PAINT MONO (650 5000);
DISPLAY INVISIBLE (650 5000);
FORCEPROP 1 LAST BODY_TYPE PLUMBING
J 2
(650 4950);
DISPLAY 1.234043 (650 4950);
PAINT GREEN (650 4950);
DISPLAY INVISIBLE (650 4950);
FORCEPROP 1 LAST HDL_TAP TRUE
J 2
(325 4875);
DISPLAY 1.234043 (325 4875);
PAINT GREEN (325 4875);
DISPLAY INVISIBLE (325 4875);
FORCEPROP 1 LAST PATH I11
J 2
(650 5000);
DISPLAY 0.936170 (650 5000);
PAINT GREEN (650 5000);
DISPLAY INVISIBLE (650 5000);
FORCEADD TAP..6
R 2
(-1750 2000);
FORCEPROP 3 LASTPIN (-1800 2000) SIG_NAME M_D_DQ<1>
J 0
(-1790 2010);
DISPLAY 0.659574 (-1790 2010);
PAINT MONO (-1790 2010);
DISPLAY INVISIBLE (-1790 2010);
FORCEPROP 1 LASTPIN (-1800 2000) BN 1
J 2
(-1750 2010);
DISPLAY 0.617021 (-1750 2010);
PAINT PINK (-1750 2010);
FORCEPROP 2 LAST CDS_LIB mstr_standard
J 2
(-1750 2000);
DISPLAY 0.787234 (-1750 2000);
PAINT MONO (-1750 2000);
DISPLAY INVISIBLE (-1750 2000);
FORCEPROP 1 LAST BODY_TYPE PLUMBING
J 2
(-1750 1950);
DISPLAY 1.234043 (-1750 1950);
PAINT GREEN (-1750 1950);
DISPLAY INVISIBLE (-1750 1950);
FORCEPROP 1 LAST HDL_TAP TRUE
J 2
(-2075 1875);
DISPLAY 1.234043 (-2075 1875);
PAINT GREEN (-2075 1875);
DISPLAY INVISIBLE (-2075 1875);
FORCEPROP 1 LAST PATH I110
J 2
(-1750 2000);
DISPLAY 0.936170 (-1750 2000);
PAINT GREEN (-1750 2000);
DISPLAY INVISIBLE (-1750 2000);
FORCEADD SCONN288_H44441004..1
(-2500 3500);
FORCEPROP 1 LAST LOCATION J4B1
J 0
(-2950 5400);
DISPLAY 0.617021 (-2950 5400);
PAINT AQUA (-2950 5400);
FORCEPROP 1 LAST MATERIAL SCONN
J 0
(-2950 5350);
DISPLAY 0.617021 (-2950 5350);
PAINT SKYBLUE (-2950 5350);
FORCEPROP 2 LASTPIN (-3000 2100) $PN 141
J 2
(-3010 2110);
DISPLAY 0.617021 (-3010 2110);
PAINT ORANGE (-3010 2110);
FORCEPROP 2 LASTPIN (-3000 3650) $PN 237
J 2
(-3010 3660);
DISPLAY 0.617021 (-3010 3660);
PAINT ORANGE (-3010 3660);
FORCEPROP 2 LASTPIN (-3000 3600) $PN 93
J 2
(-3010 3610);
DISPLAY 0.617021 (-3010 3610);
PAINT ORANGE (-3010 3610);
FORCEPROP 2 LASTPIN (-3000 3550) $PN 89
J 2
(-3010 3560);
DISPLAY 0.617021 (-3010 3560);
PAINT ORANGE (-3010 3560);
FORCEPROP 2 LASTPIN (-3000 3500) $PN 84
J 2
(-3010 3510);
DISPLAY 0.617021 (-3010 3510);
PAINT ORANGE (-3010 3510);
FORCEPROP 2 LASTPIN (-3000 1800) $PN 205
J 2
(-3010 1810);
DISPLAY 0.617021 (-3010 1810);
PAINT ORANGE (-3010 1810);
FORCEPROP 2 LASTPIN (-3000 2600) $PN 58
J 2
(-3010 2610);
DISPLAY 0.617021 (-3010 2610);
PAINT ORANGE (-3010 2610);
FORCEPROP 2 LASTPIN (-3000 2650) $PN 222
J 2
(-3010 2660);
DISPLAY 0.617021 (-3010 2660);
PAINT ORANGE (-3010 2660);
FORCEPROP 2 LASTPIN (-3000 3250) $PN 91
J 2
(-3010 3260);
DISPLAY 0.617021 (-3010 3260);
PAINT ORANGE (-3010 3260);
FORCEPROP 2 LASTPIN (-3000 3200) $PN 87
J 2
(-3010 3210);
DISPLAY 0.617021 (-3010 3210);
PAINT ORANGE (-3010 3210);
FORCEPROP 2 LASTPIN (-3000 2550) $PN 78
J 2
(-3010 2560);
DISPLAY 0.617021 (-3010 2560);
PAINT ORANGE (-3010 2560);
FORCEPROP 2 LASTPIN (-2000 5150) $PN 280
J 0
(-1990 5160);
DISPLAY 0.617021 (-1990 5160);
PAINT ORANGE (-1990 5160);
FORCEPROP 2 LASTPIN (-2000 5100) $PN 135
J 0
(-1990 5110);
DISPLAY 0.617021 (-1990 5110);
PAINT ORANGE (-1990 5110);
FORCEPROP 2 LASTPIN (-2000 5050) $PN 273
J 0
(-1990 5060);
DISPLAY 0.617021 (-1990 5060);
PAINT ORANGE (-1990 5060);
FORCEPROP 2 LASTPIN (-2000 5000) $PN 128
J 0
(-1990 5010);
DISPLAY 0.617021 (-1990 5010);
PAINT ORANGE (-1990 5010);
FORCEPROP 2 LASTPIN (-2000 4950) $PN 282
J 0
(-1990 4960);
DISPLAY 0.617021 (-1990 4960);
PAINT ORANGE (-1990 4960);
FORCEPROP 2 LASTPIN (-2000 4850) $PN 275
J 0
(-1990 4860);
DISPLAY 0.617021 (-1990 4860);
PAINT ORANGE (-1990 4860);
FORCEPROP 2 LASTPIN (-2000 4800) $PN 130
J 0
(-1990 4810);
DISPLAY 0.617021 (-1990 4810);
PAINT ORANGE (-1990 4810);
FORCEPROP 2 LASTPIN (-2000 4750) $PN 269
J 0
(-1990 4760);
DISPLAY 0.617021 (-1990 4760);
PAINT ORANGE (-1990 4760);
FORCEPROP 2 LASTPIN (-2000 4700) $PN 124
J 0
(-1990 4710);
DISPLAY 0.617021 (-1990 4710);
PAINT ORANGE (-1990 4710);
FORCEPROP 2 LASTPIN (-2000 4650) $PN 262
J 0
(-1990 4660);
DISPLAY 0.617021 (-1990 4660);
PAINT ORANGE (-1990 4660);
FORCEPROP 2 LASTPIN (-2000 4600) $PN 117
J 0
(-1990 4610);
DISPLAY 0.617021 (-1990 4610);
PAINT ORANGE (-1990 4610);
FORCEPROP 2 LASTPIN (-2000 4550) $PN 271
J 0
(-1990 4560);
DISPLAY 0.617021 (-1990 4560);
PAINT ORANGE (-1990 4560);
FORCEPROP 2 LASTPIN (-2000 4500) $PN 126
J 0
(-1990 4510);
DISPLAY 0.617021 (-1990 4510);
PAINT ORANGE (-1990 4510);
FORCEPROP 2 LASTPIN (-2000 4450) $PN 264
J 0
(-1990 4460);
DISPLAY 0.617021 (-1990 4460);
PAINT ORANGE (-1990 4460);
FORCEPROP 2 LASTPIN (-2000 4400) $PN 119
J 0
(-1990 4410);
DISPLAY 0.617021 (-1990 4410);
PAINT ORANGE (-1990 4410);
FORCEPROP 2 LASTPIN (-2000 4350) $PN 258
J 0
(-1990 4360);
DISPLAY 0.617021 (-1990 4360);
PAINT ORANGE (-1990 4360);
FORCEPROP 2 LASTPIN (-2000 4300) $PN 113
J 0
(-1990 4310);
DISPLAY 0.617021 (-1990 4310);
PAINT ORANGE (-1990 4310);
FORCEPROP 2 LASTPIN (-2000 4250) $PN 251
J 0
(-1990 4260);
DISPLAY 0.617021 (-1990 4260);
PAINT ORANGE (-1990 4260);
FORCEPROP 2 LASTPIN (-2000 4200) $PN 106
J 0
(-1990 4210);
DISPLAY 0.617021 (-1990 4210);
PAINT ORANGE (-1990 4210);
FORCEPROP 2 LASTPIN (-2000 4150) $PN 260
J 0
(-1990 4160);
DISPLAY 0.617021 (-1990 4160);
PAINT ORANGE (-1990 4160);
FORCEPROP 2 LASTPIN (-2000 4100) $PN 115
J 0
(-1990 4110);
DISPLAY 0.617021 (-1990 4110);
PAINT ORANGE (-1990 4110);
FORCEPROP 2 LASTPIN (-2000 4050) $PN 253
J 0
(-1990 4060);
DISPLAY 0.617021 (-1990 4060);
PAINT ORANGE (-1990 4060);
FORCEPROP 2 LASTPIN (-2000 3950) $PN 247
J 0
(-1990 3960);
DISPLAY 0.617021 (-1990 3960);
PAINT ORANGE (-1990 3960);
FORCEPROP 2 LASTPIN (-2000 3900) $PN 102
J 0
(-1990 3910);
DISPLAY 0.617021 (-1990 3910);
PAINT ORANGE (-1990 3910);
FORCEPROP 2 LASTPIN (-2000 3850) $PN 240
J 0
(-1990 3860);
DISPLAY 0.617021 (-1990 3860);
PAINT ORANGE (-1990 3860);
FORCEPROP 2 LASTPIN (-2000 3800) $PN 95
J 0
(-1990 3810);
DISPLAY 0.617021 (-1990 3810);
PAINT ORANGE (-1990 3810);
FORCEPROP 2 LASTPIN (-2000 3750) $PN 249
J 0
(-1990 3760);
DISPLAY 0.617021 (-1990 3760);
PAINT ORANGE (-1990 3760);
FORCEPROP 2 LASTPIN (-2000 3700) $PN 104
J 0
(-1990 3710);
DISPLAY 0.617021 (-1990 3710);
PAINT ORANGE (-1990 3710);
FORCEPROP 2 LASTPIN (-2000 3650) $PN 242
J 0
(-1990 3660);
DISPLAY 0.617021 (-1990 3660);
PAINT ORANGE (-1990 3660);
FORCEPROP 2 LASTPIN (-2000 3600) $PN 97
J 0
(-1990 3610);
DISPLAY 0.617021 (-1990 3610);
PAINT ORANGE (-1990 3610);
FORCEPROP 2 LASTPIN (-2000 3550) $PN 188
J 0
(-1990 3560);
DISPLAY 0.617021 (-1990 3560);
PAINT ORANGE (-1990 3560);
FORCEPROP 2 LASTPIN (-2000 3500) $PN 43
J 0
(-1990 3510);
DISPLAY 0.617021 (-1990 3510);
PAINT ORANGE (-1990 3510);
FORCEPROP 2 LASTPIN (-2000 3450) $PN 181
J 0
(-1990 3460);
DISPLAY 0.617021 (-1990 3460);
PAINT ORANGE (-1990 3460);
FORCEPROP 2 LASTPIN (-2000 3400) $PN 36
J 0
(-1990 3410);
DISPLAY 0.617021 (-1990 3410);
PAINT ORANGE (-1990 3410);
FORCEPROP 2 LASTPIN (-2000 3350) $PN 190
J 0
(-1990 3360);
DISPLAY 0.617021 (-1990 3360);
PAINT ORANGE (-1990 3360);
FORCEPROP 2 LASTPIN (-2000 3300) $PN 45
J 0
(-1990 3310);
DISPLAY 0.617021 (-1990 3310);
PAINT ORANGE (-1990 3310);
FORCEPROP 2 LASTPIN (-2000 3250) $PN 183
J 0
(-1990 3260);
DISPLAY 0.617021 (-1990 3260);
PAINT ORANGE (-1990 3260);
FORCEPROP 2 LASTPIN (-2000 3200) $PN 38
J 0
(-1990 3210);
DISPLAY 0.617021 (-1990 3210);
PAINT ORANGE (-1990 3210);
FORCEPROP 2 LASTPIN (-2000 3150) $PN 177
J 0
(-1990 3160);
DISPLAY 0.617021 (-1990 3160);
PAINT ORANGE (-1990 3160);
FORCEPROP 2 LASTPIN (-2000 3100) $PN 32
J 0
(-1990 3110);
DISPLAY 0.617021 (-1990 3110);
PAINT ORANGE (-1990 3110);
FORCEPROP 2 LASTPIN (-2000 3050) $PN 170
J 0
(-1990 3060);
DISPLAY 0.617021 (-1990 3060);
PAINT ORANGE (-1990 3060);
FORCEPROP 2 LASTPIN (-2000 3000) $PN 25
J 0
(-1990 3010);
DISPLAY 0.617021 (-1990 3010);
PAINT ORANGE (-1990 3010);
FORCEPROP 2 LASTPIN (-2000 2950) $PN 179
J 0
(-1990 2960);
DISPLAY 0.617021 (-1990 2960);
PAINT ORANGE (-1990 2960);
FORCEPROP 2 LASTPIN (-2000 2900) $PN 34
J 0
(-1990 2910);
DISPLAY 0.617021 (-1990 2910);
PAINT ORANGE (-1990 2910);
FORCEPROP 2 LASTPIN (-2000 2850) $PN 172
J 0
(-1990 2860);
DISPLAY 0.617021 (-1990 2860);
PAINT ORANGE (-1990 2860);
FORCEPROP 2 LASTPIN (-2000 2800) $PN 27
J 0
(-1990 2810);
DISPLAY 0.617021 (-1990 2810);
PAINT ORANGE (-1990 2810);
FORCEPROP 2 LASTPIN (-2000 2750) $PN 166
J 0
(-1990 2760);
DISPLAY 0.617021 (-1990 2760);
PAINT ORANGE (-1990 2760);
FORCEPROP 2 LASTPIN (-2000 2700) $PN 21
J 0
(-1990 2710);
DISPLAY 0.617021 (-1990 2710);
PAINT ORANGE (-1990 2710);
FORCEPROP 2 LASTPIN (-2000 2650) $PN 159
J 0
(-1990 2660);
DISPLAY 0.617021 (-1990 2660);
PAINT ORANGE (-1990 2660);
FORCEPROP 2 LASTPIN (-2000 2600) $PN 14
J 0
(-1990 2610);
DISPLAY 0.617021 (-1990 2610);
PAINT ORANGE (-1990 2610);
FORCEPROP 2 LASTPIN (-2000 2550) $PN 168
J 0
(-1990 2560);
DISPLAY 0.617021 (-1990 2560);
PAINT ORANGE (-1990 2560);
FORCEPROP 2 LASTPIN (-2000 2500) $PN 23
J 0
(-1990 2510);
DISPLAY 0.617021 (-1990 2510);
PAINT ORANGE (-1990 2510);
FORCEPROP 2 LASTPIN (-2000 2450) $PN 161
J 0
(-1990 2460);
DISPLAY 0.617021 (-1990 2460);
PAINT ORANGE (-1990 2460);
FORCEPROP 2 LASTPIN (-2000 2400) $PN 16
J 0
(-1990 2410);
DISPLAY 0.617021 (-1990 2410);
PAINT ORANGE (-1990 2410);
FORCEPROP 2 LASTPIN (-2000 2350) $PN 155
J 0
(-1990 2360);
DISPLAY 0.617021 (-1990 2360);
PAINT ORANGE (-1990 2360);
FORCEPROP 2 LASTPIN (-2000 2300) $PN 10
J 0
(-1990 2310);
DISPLAY 0.617021 (-1990 2310);
PAINT ORANGE (-1990 2310);
FORCEPROP 2 LASTPIN (-2000 2250) $PN 148
J 0
(-1990 2260);
DISPLAY 0.617021 (-1990 2260);
PAINT ORANGE (-1990 2260);
FORCEPROP 2 LASTPIN (-2000 2200) $PN 3
J 0
(-1990 2210);
DISPLAY 0.617021 (-1990 2210);
PAINT ORANGE (-1990 2210);
FORCEPROP 2 LASTPIN (-2000 2150) $PN 157
J 0
(-1990 2160);
DISPLAY 0.617021 (-1990 2160);
PAINT ORANGE (-1990 2160);
FORCEPROP 2 LASTPIN (-2000 2050) $PN 150
J 0
(-1990 2060);
DISPLAY 0.617021 (-1990 2060);
PAINT ORANGE (-1990 2060);
FORCEPROP 2 LASTPIN (-2000 2000) $PN 5
J 0
(-1990 2010);
DISPLAY 0.617021 (-1990 2010);
PAINT ORANGE (-1990 2010);
FORCEPROP 2 LASTPIN (-3000 3400) $PN 203
J 2
(-3010 3410);
DISPLAY 0.617021 (-3010 3410);
PAINT ORANGE (-3010 3410);
FORCEPROP 2 LASTPIN (-3000 3350) $PN 60
J 2
(-3010 3360);
DISPLAY 0.617021 (-3010 3360);
PAINT ORANGE (-3010 3360);
FORCEPROP 2 LASTPIN (-3000 3950) $PN 218
J 2
(-3010 3960);
DISPLAY 0.617021 (-3010 3960);
PAINT ORANGE (-3010 3960);
FORCEPROP 2 LASTPIN (-3000 3900) $PN 219
J 2
(-3010 3910);
DISPLAY 0.617021 (-3010 3910);
PAINT ORANGE (-3010 3910);
FORCEPROP 2 LASTPIN (-3000 3850) $PN 74
J 2
(-3010 3860);
DISPLAY 0.617021 (-3010 3860);
PAINT ORANGE (-3010 3860);
FORCEPROP 2 LASTPIN (-3000 3800) $PN 75
J 2
(-3010 3810);
DISPLAY 0.617021 (-3010 3810);
PAINT ORANGE (-3010 3810);
FORCEPROP 2 LASTPIN (-3000 3100) $PN 199
J 2
(-3010 3110);
DISPLAY 0.617021 (-3010 3110);
PAINT ORANGE (-3010 3110);
FORCEPROP 2 LASTPIN (-3000 3050) $PN 54
J 2
(-3010 3060);
DISPLAY 0.617021 (-3010 3060);
PAINT ORANGE (-3010 3060);
FORCEPROP 2 LASTPIN (-3000 3000) $PN 192
J 2
(-3010 3010);
DISPLAY 0.617021 (-3010 3010);
PAINT ORANGE (-3010 3010);
FORCEPROP 2 LASTPIN (-3000 2900) $PN 201
J 2
(-3010 2910);
DISPLAY 0.617021 (-3010 2910);
PAINT ORANGE (-3010 2910);
FORCEPROP 2 LASTPIN (-3000 2850) $PN 56
J 2
(-3010 2860);
DISPLAY 0.617021 (-3010 2860);
PAINT ORANGE (-3010 2860);
FORCEPROP 2 LASTPIN (-3000 2800) $PN 194
J 2
(-3010 2810);
DISPLAY 0.617021 (-3010 2810);
PAINT ORANGE (-3010 2810);
FORCEPROP 2 LASTPIN (-3000 2750) $PN 49
J 2
(-3010 2760);
DISPLAY 0.617021 (-3010 2760);
PAINT ORANGE (-3010 2760);
FORCEPROP 2 LASTPIN (-3000 3700) $PN 235
J 2
(-3010 3710);
DISPLAY 0.617021 (-3010 3710);
PAINT ORANGE (-3010 3710);
FORCEPROP 2 LASTPIN (-3000 4050) $PN 63
J 2
(-3010 4060);
DISPLAY 0.617021 (-3010 4060);
PAINT ORANGE (-3010 4060);
FORCEPROP 2 LASTPIN (-3000 4200) $PN 224
J 2
(-3010 4210);
DISPLAY 0.617021 (-3010 4210);
PAINT ORANGE (-3010 4210);
FORCEPROP 2 LASTPIN (-3000 4150) $PN 81
J 2
(-3010 4160);
DISPLAY 0.617021 (-3010 4160);
PAINT ORANGE (-3010 4160);
FORCEPROP 2 LASTPIN (-3000 2500) $PN 208
J 2
(-3010 2510);
DISPLAY 0.617021 (-3010 2510);
PAINT ORANGE (-3010 2510);
FORCEPROP 2 LASTPIN (-3000 2450) $PN 62
J 2
(-3010 2460);
DISPLAY 0.617021 (-3010 2460);
PAINT ORANGE (-3010 2460);
FORCEPROP 2 LASTPIN (-3000 5150) $PN 234
J 2
(-3010 5160);
DISPLAY 0.617021 (-3010 5160);
PAINT ORANGE (-3010 5160);
FORCEPROP 2 LASTPIN (-3000 5100) $PN 82
J 2
(-3010 5110);
DISPLAY 0.617021 (-3010 5110);
PAINT ORANGE (-3010 5110);
FORCEPROP 2 LASTPIN (-3000 4950) $PN 232
J 2
(-3010 4960);
DISPLAY 0.617021 (-3010 4960);
PAINT ORANGE (-3010 4960);
FORCEPROP 2 LASTPIN (-3000 4900) $PN 65
J 2
(-3010 4910);
DISPLAY 0.617021 (-3010 4910);
PAINT ORANGE (-3010 4910);
FORCEPROP 2 LASTPIN (-3000 4850) $PN 210
J 2
(-3010 4860);
DISPLAY 0.617021 (-3010 4860);
PAINT ORANGE (-3010 4860);
FORCEPROP 2 LASTPIN (-3000 4800) $PN 225
J 2
(-3010 4810);
DISPLAY 0.617021 (-3010 4810);
PAINT ORANGE (-3010 4810);
FORCEPROP 2 LASTPIN (-3000 4750) $PN 66
J 2
(-3010 4760);
DISPLAY 0.617021 (-3010 4760);
PAINT ORANGE (-3010 4760);
FORCEPROP 2 LASTPIN (-3000 4700) $PN 68
J 2
(-3010 4710);
DISPLAY 0.617021 (-3010 4710);
PAINT ORANGE (-3010 4710);
FORCEPROP 2 LASTPIN (-3000 4650) $PN 211
J 2
(-3010 4660);
DISPLAY 0.617021 (-3010 4660);
PAINT ORANGE (-3010 4660);
FORCEPROP 2 LASTPIN (-3000 4600) $PN 69
J 2
(-3010 4610);
DISPLAY 0.617021 (-3010 4610);
PAINT ORANGE (-3010 4610);
FORCEPROP 2 LASTPIN (-3000 4550) $PN 213
J 2
(-3010 4560);
DISPLAY 0.617021 (-3010 4560);
PAINT ORANGE (-3010 4560);
FORCEPROP 2 LASTPIN (-3000 4500) $PN 214
J 2
(-3010 4510);
DISPLAY 0.617021 (-3010 4510);
PAINT ORANGE (-3010 4510);
FORCEPROP 2 LASTPIN (-3000 4450) $PN 71
J 2
(-3010 4460);
DISPLAY 0.617021 (-3010 4460);
PAINT ORANGE (-3010 4460);
FORCEPROP 2 LASTPIN (-3000 4350) $PN 72
J 2
(-3010 4360);
DISPLAY 0.617021 (-3010 4360);
PAINT ORANGE (-3010 4360);
FORCEPROP 2 LASTPIN (-3000 4300) $PN 79
J 2
(-3010 4310);
DISPLAY 0.617021 (-3010 4310);
PAINT ORANGE (-3010 4310);
FORCEPROP 2 LASTPIN (-2000 4900) $PN 137
J 0
(-1990 4910);
DISPLAY 0.617021 (-1990 4910);
PAINT ORANGE (-1990 4910);
FORCEPROP 2 LASTPIN (-3000 5050) $PN 86
J 2
(-3010 5060);
DISPLAY 0.617021 (-3010 5060);
PAINT ORANGE (-3010 5060);
FORCEPROP 2 LASTPIN (-3000 4400) $PN 216
J 2
(-3010 4410);
DISPLAY 0.617021 (-3010 4410);
PAINT ORANGE (-3010 4410);
FORCEPROP 2 LASTPIN (-3000 4100) $PN 207
J 2
(-3010 4110);
DISPLAY 0.617021 (-3010 4110);
PAINT ORANGE (-3010 4110);
FORCEPROP 2 LASTPIN (-3000 2200) $PN 139
J 2
(-3010 2210);
DISPLAY 0.617021 (-3010 2210);
PAINT ORANGE (-3010 2210);
FORCEPROP 2 LASTPIN (-3000 2150) $PN 285
J 2
(-3010 2160);
DISPLAY 0.617021 (-3010 2160);
PAINT ORANGE (-3010 2160);
FORCEPROP 2 LASTPIN (-3000 1900) $PN 144
J 2
(-3010 1910);
DISPLAY 0.617021 (-3010 1910);
PAINT ORANGE (-3010 1910);
FORCEPROP 2 LASTPIN (-3000 1850) $PN 227
J 2
(-3010 1860);
DISPLAY 0.617021 (-3010 1860);
PAINT ORANGE (-3010 1860);
FORCEPROP 2 LASTPIN (-2000 2100) $PN 12
J 0
(-1990 2110);
DISPLAY 0.617021 (-1990 2110);
PAINT ORANGE (-1990 2110);
FORCEPROP 1 LAST PART_NUMBER H44441-004
J 0
(-2950 1500);
DISPLAY 0.617021 (-2950 1500);
PAINT BLUE (-2950 1500);
FORCEPROP 2 LASTPIN (-3000 5000) $PN 228
J 2
(-3010 5010);
DISPLAY 0.617021 (-3010 5010);
PAINT ORANGE (-3010 5010);
FORCEPROP 2 LASTPIN (-3000 2950) $PN 47
J 2
(-3010 2960);
DISPLAY 0.617021 (-3010 2960);
PAINT ORANGE (-3010 2960);
FORCEPROP 2 LASTPIN (-3000 2300) $PN 238
J 2
(-3010 2310);
DISPLAY 0.617021 (-3010 2310);
PAINT ORANGE (-3010 2310);
FORCEPROP 2 LASTPIN (-3000 2250) $PN 140
J 2
(-3010 2260);
DISPLAY 0.617021 (-3010 2260);
PAINT ORANGE (-3010 2260);
FORCEPROP 2 LASTPIN (-3000 1700) $PN 230
J 2
(-3010 1710);
DISPLAY 0.617021 (-3010 1710);
PAINT ORANGE (-3010 1710);
FORCEPROP 2 LASTPIN (-2000 4000) $PN 108
J 0
(-1990 4010);
DISPLAY 0.617021 (-1990 4010);
PAINT ORANGE (-1990 4010);
FORCEPROP 2 LASTPIN (-3000 2350) $PN 284
J 2
(-3010 2360);
DISPLAY 0.617021 (-3010 2360);
PAINT ORANGE (-3010 2360);
FORCEPROP 2 LASTPIN (-3000 2000) $PN 146
J 2
(-3010 2010);
DISPLAY 0.617021 (-3010 2010);
PAINT ORANGE (-3010 2010);
FORCEPROP 1 LAST PACK_TYPE PIP
J 0
(-2950 5450);
PAINT SKYBLUE (-2950 5450);
DISPLAY INVISIBLE (-2950 5450);
FORCEPROP 2 LAST BOM_COST MEM
J 0
(-2450 2850);
PAINT ORANGE (-2450 2850);
DISPLAY INVISIBLE (-2450 2850);
FORCEPROP 2 LAST CDS_LIB mstr_sconn
J 0
(-2500 3500);
PAINT ORANGE (-2500 3500);
DISPLAY INVISIBLE (-2500 3500);
FORCEPROP 2 LAST SEC_TYPE PIP
J 0
(-2950 5450);
DISPLAY 1.021277 (-2950 5450);
PAINT ORANGE (-2950 5450);
DISPLAY INVISIBLE (-2950 5450);
FORCEPROP 2 LAST SEC 1
J 0
(-2950 5450);
DISPLAY 0.680851 (-2950 5450);
PAINT MONO (-2950 5450);
DISPLAY INVISIBLE (-2950 5450);
FORCEPROP 2 LAST CDS_LOCATION J4B1
J 0
(-2950 5400);
DISPLAY 0.617021 (-2950 5400);
PAINT AQUA (-2950 5400);
DISPLAY INVISIBLE (-2950 5400);
FORCEPROP 1 LAST PATH I111
J 0
(-2500 5350);
PAINT GREEN (-2500 5350);
DISPLAY INVISIBLE (-2500 5350);
FORCEPROP 2 LAST ROOM DDR4_CH_D
J 0
(-2450 2850);
PAINT ORANGE (-2450 2850);
DISPLAY INVISIBLE (-2450 2850);
FORCEADD TAP..6
(-3250 5150);
FORCEPROP 3 LASTPIN (-3200 5150) SIG_NAME M_D_MA<17>
J 0
(-3190 5160);
DISPLAY 0.659574 (-3190 5160);
PAINT MONO (-3190 5160);
DISPLAY INVISIBLE (-3190 5160);
FORCEPROP 1 LASTPIN (-3200 5150) BN 17
J 0
(-3250 5160);
DISPLAY 0.617021 (-3250 5160);
PAINT PINK (-3250 5160);
FORCEPROP 2 LAST CDS_LIB mstr_standard
J 0
(-3250 5150);
DISPLAY 0.787234 (-3250 5150);
PAINT MONO (-3250 5150);
DISPLAY INVISIBLE (-3250 5150);
FORCEPROP 1 LAST BODY_TYPE PLUMBING
J 0
(-3250 5100);
DISPLAY 1.234043 (-3250 5100);
PAINT GREEN (-3250 5100);
DISPLAY INVISIBLE (-3250 5100);
FORCEPROP 1 LAST HDL_TAP TRUE
J 0
(-2925 5025);
DISPLAY 1.234043 (-2925 5025);
PAINT GREEN (-2925 5025);
DISPLAY INVISIBLE (-2925 5025);
FORCEPROP 1 LAST PATH I112
J 0
(-3250 5150);
DISPLAY 0.936170 (-3250 5150);
PAINT GREEN (-3250 5150);
DISPLAY INVISIBLE (-3250 5150);
FORCEADD TAP..6
(-3250 5100);
FORCEPROP 3 LASTPIN (-3200 5100) SIG_NAME M_D_MA<16>
J 0
(-3190 5110);
DISPLAY 0.659574 (-3190 5110);
PAINT MONO (-3190 5110);
DISPLAY INVISIBLE (-3190 5110);
FORCEPROP 1 LASTPIN (-3200 5100) BN 16
J 0
(-3250 5110);
DISPLAY 0.617021 (-3250 5110);
PAINT PINK (-3250 5110);
FORCEPROP 2 LAST CDS_LIB mstr_standard
J 2
(-3250 5100);
DISPLAY 0.787234 (-3250 5100);
PAINT MONO (-3250 5100);
DISPLAY INVISIBLE (-3250 5100);
FORCEPROP 1 LAST BODY_TYPE PLUMBING
J 0
(-3250 5050);
DISPLAY 1.234043 (-3250 5050);
PAINT GREEN (-3250 5050);
DISPLAY INVISIBLE (-3250 5050);
FORCEPROP 1 LAST HDL_TAP TRUE
J 0
(-2925 4975);
DISPLAY 1.234043 (-2925 4975);
PAINT GREEN (-2925 4975);
DISPLAY INVISIBLE (-2925 4975);
FORCEPROP 1 LAST PATH I113
J 0
(-3250 5100);
DISPLAY 0.936170 (-3250 5100);
PAINT GREEN (-3250 5100);
DISPLAY INVISIBLE (-3250 5100);
FORCEADD TAP..6
(-3250 5050);
FORCEPROP 3 LASTPIN (-3200 5050) SIG_NAME M_D_MA<15>
J 0
(-3190 5060);
DISPLAY 0.659574 (-3190 5060);
PAINT MONO (-3190 5060);
DISPLAY INVISIBLE (-3190 5060);
FORCEPROP 1 LASTPIN (-3200 5050) BN 15
J 0
(-3250 5060);
DISPLAY 0.617021 (-3250 5060);
PAINT PINK (-3250 5060);
FORCEPROP 2 LAST CDS_LIB mstr_standard
J 2
(-3250 5050);
DISPLAY 0.787234 (-3250 5050);
PAINT MONO (-3250 5050);
DISPLAY INVISIBLE (-3250 5050);
FORCEPROP 1 LAST BODY_TYPE PLUMBING
J 0
(-3250 5000);
DISPLAY 1.234043 (-3250 5000);
PAINT GREEN (-3250 5000);
DISPLAY INVISIBLE (-3250 5000);
FORCEPROP 1 LAST HDL_TAP TRUE
J 0
(-2925 4925);
DISPLAY 1.234043 (-2925 4925);
PAINT GREEN (-2925 4925);
DISPLAY INVISIBLE (-2925 4925);
FORCEPROP 1 LAST PATH I114
J 0
(-3250 5050);
DISPLAY 0.936170 (-3250 5050);
PAINT GREEN (-3250 5050);
DISPLAY INVISIBLE (-3250 5050);
FORCEADD TAP..6
(-3250 5000);
FORCEPROP 3 LASTPIN (-3200 5000) SIG_NAME M_D_MA<14>
J 0
(-3190 5010);
DISPLAY 0.659574 (-3190 5010);
PAINT MONO (-3190 5010);
DISPLAY INVISIBLE (-3190 5010);
FORCEPROP 1 LASTPIN (-3200 5000) BN 14
J 0
(-3250 5010);
DISPLAY 0.617021 (-3250 5010);
PAINT PINK (-3250 5010);
FORCEPROP 2 LAST CDS_LIB mstr_standard
J 2
(-3250 5000);
DISPLAY 0.787234 (-3250 5000);
PAINT MONO (-3250 5000);
DISPLAY INVISIBLE (-3250 5000);
FORCEPROP 1 LAST BODY_TYPE PLUMBING
J 0
(-3250 4950);
DISPLAY 1.234043 (-3250 4950);
PAINT GREEN (-3250 4950);
DISPLAY INVISIBLE (-3250 4950);
FORCEPROP 1 LAST HDL_TAP TRUE
J 0
(-2925 4875);
DISPLAY 1.234043 (-2925 4875);
PAINT GREEN (-2925 4875);
DISPLAY INVISIBLE (-2925 4875);
FORCEPROP 1 LAST PATH I115
J 0
(-3250 5000);
DISPLAY 0.936170 (-3250 5000);
PAINT GREEN (-3250 5000);
DISPLAY INVISIBLE (-3250 5000);
FORCEADD TAP..6
(-3250 4950);
FORCEPROP 3 LASTPIN (-3200 4950) SIG_NAME M_D_MA<13>
J 0
(-3190 4960);
DISPLAY 0.659574 (-3190 4960);
PAINT MONO (-3190 4960);
DISPLAY INVISIBLE (-3190 4960);
FORCEPROP 1 LASTPIN (-3200 4950) BN 13
J 0
(-3250 4960);
DISPLAY 0.617021 (-3250 4960);
PAINT PINK (-3250 4960);
FORCEPROP 2 LAST CDS_LIB mstr_standard
J 2
(-3250 4950);
DISPLAY 0.787234 (-3250 4950);
PAINT MONO (-3250 4950);
DISPLAY INVISIBLE (-3250 4950);
FORCEPROP 1 LAST BODY_TYPE PLUMBING
J 0
(-3250 4900);
DISPLAY 1.234043 (-3250 4900);
PAINT GREEN (-3250 4900);
DISPLAY INVISIBLE (-3250 4900);
FORCEPROP 1 LAST HDL_TAP TRUE
J 0
(-2925 4825);
DISPLAY 1.234043 (-2925 4825);
PAINT GREEN (-2925 4825);
DISPLAY INVISIBLE (-2925 4825);
FORCEPROP 1 LAST PATH I116
J 0
(-3250 4950);
DISPLAY 0.936170 (-3250 4950);
PAINT GREEN (-3250 4950);
DISPLAY INVISIBLE (-3250 4950);
FORCEADD TAP..6
(-3250 4900);
FORCEPROP 3 LASTPIN (-3200 4900) SIG_NAME M_D_MA<12>
J 0
(-3190 4910);
DISPLAY 0.659574 (-3190 4910);
PAINT MONO (-3190 4910);
DISPLAY INVISIBLE (-3190 4910);
FORCEPROP 1 LASTPIN (-3200 4900) BN 12
J 0
(-3250 4910);
DISPLAY 0.617021 (-3250 4910);
PAINT PINK (-3250 4910);
FORCEPROP 2 LAST CDS_LIB mstr_standard
J 2
(-3250 4900);
DISPLAY 0.787234 (-3250 4900);
PAINT MONO (-3250 4900);
DISPLAY INVISIBLE (-3250 4900);
FORCEPROP 1 LAST BODY_TYPE PLUMBING
J 0
(-3250 4850);
DISPLAY 1.234043 (-3250 4850);
PAINT GREEN (-3250 4850);
DISPLAY INVISIBLE (-3250 4850);
FORCEPROP 1 LAST HDL_TAP TRUE
J 0
(-2925 4775);
DISPLAY 1.234043 (-2925 4775);
PAINT GREEN (-2925 4775);
DISPLAY INVISIBLE (-2925 4775);
FORCEPROP 1 LAST PATH I117
J 0
(-3250 4900);
DISPLAY 0.936170 (-3250 4900);
PAINT GREEN (-3250 4900);
DISPLAY INVISIBLE (-3250 4900);
FORCEADD TAP..6
(-3250 4850);
FORCEPROP 3 LASTPIN (-3200 4850) SIG_NAME M_D_MA<11>
J 0
(-3190 4860);
DISPLAY 0.659574 (-3190 4860);
PAINT MONO (-3190 4860);
DISPLAY INVISIBLE (-3190 4860);
FORCEPROP 1 LASTPIN (-3200 4850) BN 11
J 0
(-3250 4860);
DISPLAY 0.617021 (-3250 4860);
PAINT PINK (-3250 4860);
FORCEPROP 2 LAST CDS_LIB mstr_standard
J 2
(-3250 4850);
DISPLAY 0.787234 (-3250 4850);
PAINT MONO (-3250 4850);
DISPLAY INVISIBLE (-3250 4850);
FORCEPROP 1 LAST BODY_TYPE PLUMBING
J 0
(-3250 4800);
DISPLAY 1.234043 (-3250 4800);
PAINT GREEN (-3250 4800);
DISPLAY INVISIBLE (-3250 4800);
FORCEPROP 1 LAST HDL_TAP TRUE
J 0
(-2925 4725);
DISPLAY 1.234043 (-2925 4725);
PAINT GREEN (-2925 4725);
DISPLAY INVISIBLE (-2925 4725);
FORCEPROP 1 LAST PATH I118
J 0
(-3250 4850);
DISPLAY 0.936170 (-3250 4850);
PAINT GREEN (-3250 4850);
DISPLAY INVISIBLE (-3250 4850);
FORCEADD TAP..6
(-3250 4800);
FORCEPROP 3 LASTPIN (-3200 4800) SIG_NAME M_D_MA<10>
J 0
(-3190 4810);
DISPLAY 0.659574 (-3190 4810);
PAINT MONO (-3190 4810);
DISPLAY INVISIBLE (-3190 4810);
FORCEPROP 1 LASTPIN (-3200 4800) BN 10
J 0
(-3250 4810);
DISPLAY 0.617021 (-3250 4810);
PAINT PINK (-3250 4810);
FORCEPROP 2 LAST CDS_LIB mstr_standard
J 2
(-3250 4800);
DISPLAY 0.787234 (-3250 4800);
PAINT MONO (-3250 4800);
DISPLAY INVISIBLE (-3250 4800);
FORCEPROP 1 LAST BODY_TYPE PLUMBING
J 0
(-3250 4750);
DISPLAY 1.234043 (-3250 4750);
PAINT GREEN (-3250 4750);
DISPLAY INVISIBLE (-3250 4750);
FORCEPROP 1 LAST HDL_TAP TRUE
J 0
(-2925 4675);
DISPLAY 1.234043 (-2925 4675);
PAINT GREEN (-2925 4675);
DISPLAY INVISIBLE (-2925 4675);
FORCEPROP 1 LAST PATH I119
J 0
(-3250 4800);
DISPLAY 0.936170 (-3250 4800);
PAINT GREEN (-3250 4800);
DISPLAY INVISIBLE (-3250 4800);
FORCEADD TAP..6
R 2
(650 4900);
FORCEPROP 3 LASTPIN (600 4900) SIG_NAME M_D_DQS_DP<14>
J 0
(610 4910);
DISPLAY 0.659574 (610 4910);
PAINT MONO (610 4910);
DISPLAY INVISIBLE (610 4910);
FORCEPROP 1 LASTPIN (600 4900) BN 14
J 2
(650 4910);
DISPLAY 0.617021 (650 4910);
PAINT PINK (650 4910);
FORCEPROP 2 LAST CDS_LIB mstr_standard
J 0
(650 4900);
DISPLAY 0.787234 (650 4900);
PAINT MONO (650 4900);
DISPLAY INVISIBLE (650 4900);
FORCEPROP 1 LAST BODY_TYPE PLUMBING
J 2
(650 4850);
DISPLAY 1.234043 (650 4850);
PAINT GREEN (650 4850);
DISPLAY INVISIBLE (650 4850);
FORCEPROP 1 LAST HDL_TAP TRUE
J 2
(325 4775);
DISPLAY 1.234043 (325 4775);
PAINT GREEN (325 4775);
DISPLAY INVISIBLE (325 4775);
FORCEPROP 1 LAST PATH I12
J 2
(650 4900);
DISPLAY 0.936170 (650 4900);
PAINT GREEN (650 4900);
DISPLAY INVISIBLE (650 4900);
FORCEADD TAP..6
(-3250 4750);
FORCEPROP 3 LASTPIN (-3200 4750) SIG_NAME M_D_MA<9>
J 0
(-3190 4760);
DISPLAY 0.659574 (-3190 4760);
PAINT MONO (-3190 4760);
DISPLAY INVISIBLE (-3190 4760);
FORCEPROP 1 LASTPIN (-3200 4750) BN 9
J 0
(-3250 4760);
DISPLAY 0.617021 (-3250 4760);
PAINT PINK (-3250 4760);
FORCEPROP 2 LAST CDS_LIB mstr_standard
J 2
(-3250 4750);
DISPLAY 0.787234 (-3250 4750);
PAINT MONO (-3250 4750);
DISPLAY INVISIBLE (-3250 4750);
FORCEPROP 1 LAST BODY_TYPE PLUMBING
J 0
(-3250 4700);
DISPLAY 1.234043 (-3250 4700);
PAINT GREEN (-3250 4700);
DISPLAY INVISIBLE (-3250 4700);
FORCEPROP 1 LAST HDL_TAP TRUE
J 0
(-2925 4625);
DISPLAY 1.234043 (-2925 4625);
PAINT GREEN (-2925 4625);
DISPLAY INVISIBLE (-2925 4625);
FORCEPROP 1 LAST PATH I120
J 0
(-3250 4750);
DISPLAY 0.936170 (-3250 4750);
PAINT GREEN (-3250 4750);
DISPLAY INVISIBLE (-3250 4750);
FORCEADD TAP..6
(-3250 4700);
FORCEPROP 3 LASTPIN (-3200 4700) SIG_NAME M_D_MA<8>
J 0
(-3190 4710);
DISPLAY 0.659574 (-3190 4710);
PAINT MONO (-3190 4710);
DISPLAY INVISIBLE (-3190 4710);
FORCEPROP 1 LASTPIN (-3200 4700) BN 8
J 0
(-3250 4710);
DISPLAY 0.617021 (-3250 4710);
PAINT PINK (-3250 4710);
FORCEPROP 2 LAST CDS_LIB mstr_standard
J 2
(-3250 4700);
DISPLAY 0.787234 (-3250 4700);
PAINT MONO (-3250 4700);
DISPLAY INVISIBLE (-3250 4700);
FORCEPROP 1 LAST BODY_TYPE PLUMBING
J 0
(-3250 4650);
DISPLAY 1.234043 (-3250 4650);
PAINT GREEN (-3250 4650);
DISPLAY INVISIBLE (-3250 4650);
FORCEPROP 1 LAST HDL_TAP TRUE
J 0
(-2925 4575);
DISPLAY 1.234043 (-2925 4575);
PAINT GREEN (-2925 4575);
DISPLAY INVISIBLE (-2925 4575);
FORCEPROP 1 LAST PATH I121
J 0
(-3250 4700);
DISPLAY 0.936170 (-3250 4700);
PAINT GREEN (-3250 4700);
DISPLAY INVISIBLE (-3250 4700);
FORCEADD TAP..6
(-3250 4650);
FORCEPROP 3 LASTPIN (-3200 4650) SIG_NAME M_D_MA<7>
J 0
(-3190 4660);
DISPLAY 0.659574 (-3190 4660);
PAINT MONO (-3190 4660);
DISPLAY INVISIBLE (-3190 4660);
FORCEPROP 1 LASTPIN (-3200 4650) BN 7
J 0
(-3250 4660);
DISPLAY 0.617021 (-3250 4660);
PAINT PINK (-3250 4660);
FORCEPROP 2 LAST CDS_LIB mstr_standard
J 2
(-3250 4650);
DISPLAY 0.787234 (-3250 4650);
PAINT MONO (-3250 4650);
DISPLAY INVISIBLE (-3250 4650);
FORCEPROP 1 LAST BODY_TYPE PLUMBING
J 0
(-3250 4600);
DISPLAY 1.234043 (-3250 4600);
PAINT GREEN (-3250 4600);
DISPLAY INVISIBLE (-3250 4600);
FORCEPROP 1 LAST HDL_TAP TRUE
J 0
(-2925 4525);
DISPLAY 1.234043 (-2925 4525);
PAINT GREEN (-2925 4525);
DISPLAY INVISIBLE (-2925 4525);
FORCEPROP 1 LAST PATH I122
J 0
(-3250 4650);
DISPLAY 0.936170 (-3250 4650);
PAINT GREEN (-3250 4650);
DISPLAY INVISIBLE (-3250 4650);
FORCEADD TAP..6
(-3250 4600);
FORCEPROP 3 LASTPIN (-3200 4600) SIG_NAME M_D_MA<6>
J 0
(-3190 4610);
DISPLAY 0.659574 (-3190 4610);
PAINT MONO (-3190 4610);
DISPLAY INVISIBLE (-3190 4610);
FORCEPROP 1 LASTPIN (-3200 4600) BN 6
J 0
(-3250 4610);
DISPLAY 0.617021 (-3250 4610);
PAINT PINK (-3250 4610);
FORCEPROP 2 LAST CDS_LIB mstr_standard
J 2
(-3250 4600);
DISPLAY 0.787234 (-3250 4600);
PAINT MONO (-3250 4600);
DISPLAY INVISIBLE (-3250 4600);
FORCEPROP 1 LAST BODY_TYPE PLUMBING
J 0
(-3250 4550);
DISPLAY 1.234043 (-3250 4550);
PAINT GREEN (-3250 4550);
DISPLAY INVISIBLE (-3250 4550);
FORCEPROP 1 LAST HDL_TAP TRUE
J 0
(-2925 4475);
DISPLAY 1.234043 (-2925 4475);
PAINT GREEN (-2925 4475);
DISPLAY INVISIBLE (-2925 4475);
FORCEPROP 1 LAST PATH I123
J 0
(-3250 4600);
DISPLAY 0.936170 (-3250 4600);
PAINT GREEN (-3250 4600);
DISPLAY INVISIBLE (-3250 4600);
FORCEADD TAP..6
(-3250 4550);
FORCEPROP 3 LASTPIN (-3200 4550) SIG_NAME M_D_MA<5>
J 0
(-3190 4560);
DISPLAY 0.659574 (-3190 4560);
PAINT MONO (-3190 4560);
DISPLAY INVISIBLE (-3190 4560);
FORCEPROP 1 LASTPIN (-3200 4550) BN 5
J 0
(-3250 4560);
DISPLAY 0.617021 (-3250 4560);
PAINT PINK (-3250 4560);
FORCEPROP 2 LAST CDS_LIB mstr_standard
J 2
(-3250 4550);
DISPLAY 0.787234 (-3250 4550);
PAINT MONO (-3250 4550);
DISPLAY INVISIBLE (-3250 4550);
FORCEPROP 1 LAST BODY_TYPE PLUMBING
J 0
(-3250 4500);
DISPLAY 1.234043 (-3250 4500);
PAINT GREEN (-3250 4500);
DISPLAY INVISIBLE (-3250 4500);
FORCEPROP 1 LAST HDL_TAP TRUE
J 0
(-2925 4425);
DISPLAY 1.234043 (-2925 4425);
PAINT GREEN (-2925 4425);
DISPLAY INVISIBLE (-2925 4425);
FORCEPROP 1 LAST PATH I124
J 0
(-3250 4550);
DISPLAY 0.936170 (-3250 4550);
PAINT GREEN (-3250 4550);
DISPLAY INVISIBLE (-3250 4550);
FORCEADD TAP..6
(-3250 4500);
FORCEPROP 3 LASTPIN (-3200 4500) SIG_NAME M_D_MA<4>
J 0
(-3190 4510);
DISPLAY 0.659574 (-3190 4510);
PAINT MONO (-3190 4510);
DISPLAY INVISIBLE (-3190 4510);
FORCEPROP 1 LASTPIN (-3200 4500) BN 4
J 0
(-3250 4510);
DISPLAY 0.617021 (-3250 4510);
PAINT PINK (-3250 4510);
FORCEPROP 2 LAST CDS_LIB mstr_standard
J 2
(-3250 4500);
DISPLAY 0.787234 (-3250 4500);
PAINT MONO (-3250 4500);
DISPLAY INVISIBLE (-3250 4500);
FORCEPROP 1 LAST BODY_TYPE PLUMBING
J 0
(-3250 4450);
DISPLAY 1.234043 (-3250 4450);
PAINT GREEN (-3250 4450);
DISPLAY INVISIBLE (-3250 4450);
FORCEPROP 1 LAST HDL_TAP TRUE
J 0
(-2925 4375);
DISPLAY 1.234043 (-2925 4375);
PAINT GREEN (-2925 4375);
DISPLAY INVISIBLE (-2925 4375);
FORCEPROP 1 LAST PATH I125
J 0
(-3250 4500);
DISPLAY 0.936170 (-3250 4500);
PAINT GREEN (-3250 4500);
DISPLAY INVISIBLE (-3250 4500);
FORCEADD TAP..6
(-3250 4450);
FORCEPROP 3 LASTPIN (-3200 4450) SIG_NAME M_D_MA<3>
J 0
(-3190 4460);
DISPLAY 0.659574 (-3190 4460);
PAINT MONO (-3190 4460);
DISPLAY INVISIBLE (-3190 4460);
FORCEPROP 1 LASTPIN (-3200 4450) BN 3
J 0
(-3250 4460);
DISPLAY 0.617021 (-3250 4460);
PAINT PINK (-3250 4460);
FORCEPROP 2 LAST CDS_LIB mstr_standard
J 2
(-3250 4450);
DISPLAY 0.787234 (-3250 4450);
PAINT MONO (-3250 4450);
DISPLAY INVISIBLE (-3250 4450);
FORCEPROP 1 LAST BODY_TYPE PLUMBING
J 0
(-3250 4400);
DISPLAY 1.234043 (-3250 4400);
PAINT GREEN (-3250 4400);
DISPLAY INVISIBLE (-3250 4400);
FORCEPROP 1 LAST HDL_TAP TRUE
J 0
(-2925 4325);
DISPLAY 1.234043 (-2925 4325);
PAINT GREEN (-2925 4325);
DISPLAY INVISIBLE (-2925 4325);
FORCEPROP 1 LAST PATH I126
J 0
(-3250 4450);
DISPLAY 0.936170 (-3250 4450);
PAINT GREEN (-3250 4450);
DISPLAY INVISIBLE (-3250 4450);
FORCEADD TAP..6
(-3250 4400);
FORCEPROP 3 LASTPIN (-3200 4400) SIG_NAME M_D_MA<2>
J 0
(-3190 4410);
DISPLAY 0.659574 (-3190 4410);
PAINT MONO (-3190 4410);
DISPLAY INVISIBLE (-3190 4410);
FORCEPROP 1 LASTPIN (-3200 4400) BN 2
J 0
(-3250 4410);
DISPLAY 0.617021 (-3250 4410);
PAINT PINK (-3250 4410);
FORCEPROP 2 LAST CDS_LIB mstr_standard
J 2
(-3250 4400);
DISPLAY 0.787234 (-3250 4400);
PAINT MONO (-3250 4400);
DISPLAY INVISIBLE (-3250 4400);
FORCEPROP 1 LAST BODY_TYPE PLUMBING
J 0
(-3250 4350);
DISPLAY 1.234043 (-3250 4350);
PAINT GREEN (-3250 4350);
DISPLAY INVISIBLE (-3250 4350);
FORCEPROP 1 LAST HDL_TAP TRUE
J 0
(-2925 4275);
DISPLAY 1.234043 (-2925 4275);
PAINT GREEN (-2925 4275);
DISPLAY INVISIBLE (-2925 4275);
FORCEPROP 1 LAST PATH I127
J 0
(-3250 4400);
DISPLAY 0.936170 (-3250 4400);
PAINT GREEN (-3250 4400);
DISPLAY INVISIBLE (-3250 4400);
FORCEADD TAP..6
(-3250 4350);
FORCEPROP 3 LASTPIN (-3200 4350) SIG_NAME M_D_MA<1>
J 0
(-3190 4360);
DISPLAY 0.659574 (-3190 4360);
PAINT MONO (-3190 4360);
DISPLAY INVISIBLE (-3190 4360);
FORCEPROP 1 LASTPIN (-3200 4350) BN 1
J 0
(-3250 4360);
DISPLAY 0.617021 (-3250 4360);
PAINT PINK (-3250 4360);
FORCEPROP 2 LAST CDS_LIB mstr_standard
J 2
(-3250 4350);
DISPLAY 0.787234 (-3250 4350);
PAINT MONO (-3250 4350);
DISPLAY INVISIBLE (-3250 4350);
FORCEPROP 1 LAST BODY_TYPE PLUMBING
J 0
(-3250 4300);
DISPLAY 1.234043 (-3250 4300);
PAINT GREEN (-3250 4300);
DISPLAY INVISIBLE (-3250 4300);
FORCEPROP 1 LAST HDL_TAP TRUE
J 0
(-2925 4225);
DISPLAY 1.234043 (-2925 4225);
PAINT GREEN (-2925 4225);
DISPLAY INVISIBLE (-2925 4225);
FORCEPROP 1 LAST PATH I128
J 0
(-3250 4350);
DISPLAY 0.936170 (-3250 4350);
PAINT GREEN (-3250 4350);
DISPLAY INVISIBLE (-3250 4350);
FORCEADD TAP..6
(-3250 4300);
FORCEPROP 3 LASTPIN (-3200 4300) SIG_NAME M_D_MA<0>
J 0
(-3190 4310);
DISPLAY 0.659574 (-3190 4310);
PAINT MONO (-3190 4310);
DISPLAY INVISIBLE (-3190 4310);
FORCEPROP 1 LASTPIN (-3200 4300) BN 0
J 0
(-3250 4310);
DISPLAY 0.617021 (-3250 4310);
PAINT PINK (-3250 4310);
FORCEPROP 2 LAST CDS_LIB mstr_standard
J 2
(-3250 4300);
DISPLAY 0.787234 (-3250 4300);
PAINT MONO (-3250 4300);
DISPLAY INVISIBLE (-3250 4300);
FORCEPROP 1 LAST BODY_TYPE PLUMBING
J 0
(-3250 4250);
DISPLAY 1.234043 (-3250 4250);
PAINT GREEN (-3250 4250);
DISPLAY INVISIBLE (-3250 4250);
FORCEPROP 1 LAST HDL_TAP TRUE
J 0
(-2925 4175);
DISPLAY 1.234043 (-2925 4175);
PAINT GREEN (-2925 4175);
DISPLAY INVISIBLE (-2925 4175);
FORCEPROP 1 LAST PATH I129
J 0
(-3250 4300);
DISPLAY 0.936170 (-3250 4300);
PAINT GREEN (-3250 4300);
DISPLAY INVISIBLE (-3250 4300);
FORCEADD TAP..6
R 2
(650 4800);
FORCEPROP 3 LASTPIN (600 4800) SIG_NAME M_D_DQS_DP<13>
J 0
(610 4810);
DISPLAY 0.659574 (610 4810);
PAINT MONO (610 4810);
DISPLAY INVISIBLE (610 4810);
FORCEPROP 1 LASTPIN (600 4800) BN 13
J 2
(650 4810);
DISPLAY 0.617021 (650 4810);
PAINT PINK (650 4810);
FORCEPROP 2 LAST CDS_LIB mstr_standard
J 0
(650 4800);
DISPLAY 0.787234 (650 4800);
PAINT MONO (650 4800);
DISPLAY INVISIBLE (650 4800);
FORCEPROP 1 LAST BODY_TYPE PLUMBING
J 2
(650 4750);
DISPLAY 1.234043 (650 4750);
PAINT GREEN (650 4750);
DISPLAY INVISIBLE (650 4750);
FORCEPROP 1 LAST HDL_TAP TRUE
J 2
(325 4675);
DISPLAY 1.234043 (325 4675);
PAINT GREEN (325 4675);
DISPLAY INVISIBLE (325 4675);
FORCEPROP 1 LAST PATH I13
J 2
(650 4800);
DISPLAY 0.936170 (650 4800);
PAINT GREEN (650 4800);
DISPLAY INVISIBLE (650 4800);
FORCEADD TAP..6
(-3250 4200);
FORCEPROP 3 LASTPIN (-3200 4200) SIG_NAME M_D_BA<1>
J 0
(-3190 4210);
DISPLAY 0.659574 (-3190 4210);
PAINT MONO (-3190 4210);
DISPLAY INVISIBLE (-3190 4210);
FORCEPROP 1 LASTPIN (-3200 4200) BN 1
J 0
(-3250 4210);
DISPLAY 0.617021 (-3250 4210);
PAINT PINK (-3250 4210);
FORCEPROP 2 LAST CDS_LIB mstr_standard
J 0
(-3250 4200);
DISPLAY 0.787234 (-3250 4200);
PAINT MONO (-3250 4200);
DISPLAY INVISIBLE (-3250 4200);
FORCEPROP 1 LAST BODY_TYPE PLUMBING
J 0
(-3250 4150);
DISPLAY 1.234043 (-3250 4150);
PAINT GREEN (-3250 4150);
DISPLAY INVISIBLE (-3250 4150);
FORCEPROP 1 LAST HDL_TAP TRUE
J 0
(-2925 4075);
DISPLAY 1.234043 (-2925 4075);
PAINT GREEN (-2925 4075);
DISPLAY INVISIBLE (-2925 4075);
FORCEPROP 1 LAST PATH I130
J 0
(-3250 4200);
DISPLAY 0.936170 (-3250 4200);
PAINT GREEN (-3250 4200);
DISPLAY INVISIBLE (-3250 4200);
FORCEADD OFFPAGE..1
(-4000 5200);
FORCEPROP 2 LAST $XR1 50 
J 0
(-4251 5164);
DISPLAY 0.638298 (-4251 5164);
PAINT MONO (-4251 5164);
FORCEPROP 2 LAST $XR0 26 
J 0
(-4251 5200);
DISPLAY 0.638298 (-4251 5200);
PAINT MONO (-4251 5200);
FORCEPROP 2 LAST CDS_LIB mstr_standard
J 0
(-4000 5200);
DISPLAY 0.787234 (-4000 5200);
PAINT MONO (-4000 5200);
DISPLAY INVISIBLE (-4000 5200);
FORCEPROP 1 LAST OFFPAGE TRUE
J 0
(-3675 5075);
DISPLAY 0.936170 (-3675 5075);
PAINT GREEN (-3675 5075);
DISPLAY INVISIBLE (-3675 5075);
FORCEPROP 1 LAST COMMENT_BODY TRUE
J 0
(-3875 5100);
DISPLAY 0.936170 (-3875 5100);
PAINT GREEN (-3875 5100);
DISPLAY INVISIBLE (-3875 5100);
FORCEPROP 2 LAST PATH I131
J 0
(-3950 5275);
DISPLAY 0.787234 (-3950 5275);
PAINT MONO (-3950 5275);
DISPLAY INVISIBLE (-3950 5275);
FORCEADD OFFPAGE..1
(-4000 4250);
FORCEPROP 2 LAST $XR1 50 
J 0
(-4341 4250);
DISPLAY 0.638298 (-4341 4250);
PAINT MONO (-4341 4250);
FORCEPROP 2 LAST $XR0 26 
J 0
(-4251 4250);
DISPLAY 0.638298 (-4251 4250);
PAINT MONO (-4251 4250);
FORCEPROP 2 LAST CDS_LIB mstr_standard
J 0
(-4000 4250);
DISPLAY 0.787234 (-4000 4250);
PAINT MONO (-4000 4250);
DISPLAY INVISIBLE (-4000 4250);
FORCEPROP 1 LAST OFFPAGE TRUE
J 0
(-3675 4125);
DISPLAY 0.936170 (-3675 4125);
PAINT GREEN (-3675 4125);
DISPLAY INVISIBLE (-3675 4125);
FORCEPROP 1 LAST COMMENT_BODY TRUE
J 0
(-3875 4150);
DISPLAY 0.936170 (-3875 4150);
PAINT GREEN (-3875 4150);
DISPLAY INVISIBLE (-3875 4150);
FORCEPROP 2 LAST PATH I132
J 0
(-3950 4325);
DISPLAY 0.787234 (-3950 4325);
PAINT MONO (-3950 4325);
DISPLAY INVISIBLE (-3950 4325);
FORCEADD TAP..6
(-3250 4150);
FORCEPROP 3 LASTPIN (-3200 4150) SIG_NAME M_D_BA<0>
J 0
(-3190 4160);
DISPLAY 0.659574 (-3190 4160);
PAINT MONO (-3190 4160);
DISPLAY INVISIBLE (-3190 4160);
FORCEPROP 1 LASTPIN (-3200 4150) BN 0
J 0
(-3250 4160);
DISPLAY 0.617021 (-3250 4160);
PAINT PINK (-3250 4160);
FORCEPROP 2 LAST CDS_LIB mstr_standard
J 0
(-3250 4150);
DISPLAY 0.787234 (-3250 4150);
PAINT MONO (-3250 4150);
DISPLAY INVISIBLE (-3250 4150);
FORCEPROP 1 LAST BODY_TYPE PLUMBING
J 0
(-3250 4100);
DISPLAY 1.234043 (-3250 4100);
PAINT GREEN (-3250 4100);
DISPLAY INVISIBLE (-3250 4100);
FORCEPROP 1 LAST HDL_TAP TRUE
J 0
(-2925 4025);
DISPLAY 1.234043 (-2925 4025);
PAINT GREEN (-2925 4025);
DISPLAY INVISIBLE (-2925 4025);
FORCEPROP 1 LAST PATH I133
J 0
(-3250 4150);
DISPLAY 0.936170 (-3250 4150);
PAINT GREEN (-3250 4150);
DISPLAY INVISIBLE (-3250 4150);
FORCEADD TAP..6
(-3250 4100);
FORCEPROP 3 LASTPIN (-3200 4100) SIG_NAME M_D_BG<1>
J 0
(-3190 4110);
DISPLAY 0.659574 (-3190 4110);
PAINT MONO (-3190 4110);
DISPLAY INVISIBLE (-3190 4110);
FORCEPROP 1 LASTPIN (-3200 4100) BN 1
J 0
(-3250 4110);
DISPLAY 0.617021 (-3250 4110);
PAINT PINK (-3250 4110);
FORCEPROP 2 LAST CDS_LIB mstr_standard
J 0
(-3250 4100);
DISPLAY 0.787234 (-3250 4100);
PAINT MONO (-3250 4100);
DISPLAY INVISIBLE (-3250 4100);
FORCEPROP 1 LAST BODY_TYPE PLUMBING
J 0
(-3250 4050);
DISPLAY 1.234043 (-3250 4050);
PAINT GREEN (-3250 4050);
DISPLAY INVISIBLE (-3250 4050);
FORCEPROP 1 LAST HDL_TAP TRUE
J 0
(-2925 3975);
DISPLAY 1.234043 (-2925 3975);
PAINT GREEN (-2925 3975);
DISPLAY INVISIBLE (-2925 3975);
FORCEPROP 1 LAST PATH I134
J 0
(-3250 4100);
DISPLAY 0.936170 (-3250 4100);
PAINT GREEN (-3250 4100);
DISPLAY INVISIBLE (-3250 4100);
FORCEADD TAP..6
(-3250 4050);
FORCEPROP 3 LASTPIN (-3200 4050) SIG_NAME M_D_BG<0>
J 0
(-3190 4060);
DISPLAY 0.659574 (-3190 4060);
PAINT MONO (-3190 4060);
DISPLAY INVISIBLE (-3190 4060);
FORCEPROP 1 LASTPIN (-3200 4050) BN 0
J 0
(-3250 4060);
DISPLAY 0.617021 (-3250 4060);
PAINT PINK (-3250 4060);
FORCEPROP 2 LAST CDS_LIB mstr_standard
J 0
(-3250 4050);
DISPLAY 0.787234 (-3250 4050);
PAINT MONO (-3250 4050);
DISPLAY INVISIBLE (-3250 4050);
FORCEPROP 1 LAST BODY_TYPE PLUMBING
J 0
(-3250 4000);
DISPLAY 1.234043 (-3250 4000);
PAINT GREEN (-3250 4000);
DISPLAY INVISIBLE (-3250 4000);
FORCEPROP 1 LAST HDL_TAP TRUE
J 0
(-2925 3925);
DISPLAY 1.234043 (-2925 3925);
PAINT GREEN (-2925 3925);
DISPLAY INVISIBLE (-2925 3925);
FORCEPROP 1 LAST PATH I135
J 0
(-3250 4050);
DISPLAY 0.936170 (-3250 4050);
PAINT GREEN (-3250 4050);
DISPLAY INVISIBLE (-3250 4050);
FORCEADD OFFPAGE..1
(-4000 3750);
FORCEPROP 2 LAST $XR1 50 
J 0
(-4341 3750);
DISPLAY 0.638298 (-4341 3750);
PAINT MONO (-4341 3750);
FORCEPROP 2 LAST $XR0 26 
J 0
(-4251 3750);
DISPLAY 0.638298 (-4251 3750);
PAINT MONO (-4251 3750);
FORCEPROP 2 LAST CDS_LIB mstr_standard
J 0
(-4000 3750);
DISPLAY 0.787234 (-4000 3750);
PAINT MONO (-4000 3750);
DISPLAY INVISIBLE (-4000 3750);
FORCEPROP 1 LAST OFFPAGE TRUE
J 0
(-3675 3625);
DISPLAY 0.936170 (-3675 3625);
PAINT GREEN (-3675 3625);
DISPLAY INVISIBLE (-3675 3625);
FORCEPROP 1 LAST COMMENT_BODY TRUE
J 0
(-3875 3650);
DISPLAY 0.936170 (-3875 3650);
PAINT GREEN (-3875 3650);
DISPLAY INVISIBLE (-3875 3650);
FORCEPROP 2 LAST PATH I136
J 0
(-3950 3825);
DISPLAY 0.787234 (-3950 3825);
PAINT MONO (-3950 3825);
DISPLAY INVISIBLE (-3950 3825);
FORCEADD OFFPAGE..1
(-4000 4150);
FORCEPROP 2 LAST $XR1 50 
J 0
(-4341 4150);
DISPLAY 0.638298 (-4341 4150);
PAINT MONO (-4341 4150);
FORCEPROP 2 LAST $XR0 26 
J 0
(-4251 4150);
DISPLAY 0.638298 (-4251 4150);
PAINT MONO (-4251 4150);
FORCEPROP 2 LAST CDS_LIB mstr_standard
J 0
(-4000 4150);
DISPLAY 0.787234 (-4000 4150);
PAINT MONO (-4000 4150);
DISPLAY INVISIBLE (-4000 4150);
FORCEPROP 1 LAST OFFPAGE TRUE
J 0
(-3675 4025);
DISPLAY 0.936170 (-3675 4025);
PAINT GREEN (-3675 4025);
DISPLAY INVISIBLE (-3675 4025);
FORCEPROP 1 LAST COMMENT_BODY TRUE
J 0
(-3875 4050);
DISPLAY 0.936170 (-3875 4050);
PAINT GREEN (-3875 4050);
DISPLAY INVISIBLE (-3875 4050);
FORCEPROP 2 LAST PATH I137
J 0
(-3950 4225);
DISPLAY 0.787234 (-3950 4225);
PAINT MONO (-3950 4225);
DISPLAY INVISIBLE (-3950 4225);
FORCEADD TAP..6
(-3250 3050);
FORCEPROP 3 LASTPIN (-3200 3050) SIG_NAME M_D_ECC<7>
J 0
(-3190 3060);
DISPLAY 0.659574 (-3190 3060);
PAINT MONO (-3190 3060);
DISPLAY INVISIBLE (-3190 3060);
FORCEPROP 1 LASTPIN (-3200 3050) BN 7
J 0
(-3250 3060);
DISPLAY 0.617021 (-3250 3060);
PAINT PINK (-3250 3060);
FORCEPROP 2 LAST CDS_LIB mstr_standard
J 0
(-3250 3050);
DISPLAY 0.787234 (-3250 3050);
PAINT MONO (-3250 3050);
DISPLAY INVISIBLE (-3250 3050);
FORCEPROP 1 LAST BODY_TYPE PLUMBING
J 0
(-3250 3000);
DISPLAY 1.234043 (-3250 3000);
PAINT GREEN (-3250 3000);
DISPLAY INVISIBLE (-3250 3000);
FORCEPROP 1 LAST HDL_TAP TRUE
J 0
(-2925 2925);
DISPLAY 1.234043 (-2925 2925);
PAINT GREEN (-2925 2925);
DISPLAY INVISIBLE (-2925 2925);
FORCEPROP 1 LAST PATH I138
J 0
(-3250 3050);
DISPLAY 0.936170 (-3250 3050);
PAINT GREEN (-3250 3050);
DISPLAY INVISIBLE (-3250 3050);
FORCEADD TAP..6
(-3250 3100);
FORCEPROP 3 LASTPIN (-3200 3100) SIG_NAME M_D_ECC<6>
J 0
(-3190 3110);
DISPLAY 0.659574 (-3190 3110);
PAINT MONO (-3190 3110);
DISPLAY INVISIBLE (-3190 3110);
FORCEPROP 1 LASTPIN (-3200 3100) BN 6
J 0
(-3250 3110);
DISPLAY 0.617021 (-3250 3110);
PAINT PINK (-3250 3110);
FORCEPROP 2 LAST CDS_LIB mstr_standard
J 0
(-3250 3100);
DISPLAY 0.787234 (-3250 3100);
PAINT MONO (-3250 3100);
DISPLAY INVISIBLE (-3250 3100);
FORCEPROP 1 LAST BODY_TYPE PLUMBING
J 0
(-3250 3050);
DISPLAY 1.234043 (-3250 3050);
PAINT GREEN (-3250 3050);
DISPLAY INVISIBLE (-3250 3050);
FORCEPROP 1 LAST HDL_TAP TRUE
J 0
(-2925 2975);
DISPLAY 1.234043 (-2925 2975);
PAINT GREEN (-2925 2975);
DISPLAY INVISIBLE (-2925 2975);
FORCEPROP 1 LAST PATH I139
J 0
(-3250 3100);
DISPLAY 0.936170 (-3250 3100);
PAINT GREEN (-3250 3100);
DISPLAY INVISIBLE (-3250 3100);
FORCEADD TAP..6
R 2
(650 4600);
FORCEPROP 3 LASTPIN (600 4600) SIG_NAME M_D_DQS_DP<11>
J 0
(610 4610);
DISPLAY 0.659574 (610 4610);
PAINT MONO (610 4610);
DISPLAY INVISIBLE (610 4610);
FORCEPROP 1 LASTPIN (600 4600) BN 11
J 2
(650 4610);
DISPLAY 0.617021 (650 4610);
PAINT PINK (650 4610);
FORCEPROP 2 LAST CDS_LIB mstr_standard
J 0
(650 4600);
DISPLAY 0.787234 (650 4600);
PAINT MONO (650 4600);
DISPLAY INVISIBLE (650 4600);
FORCEPROP 1 LAST BODY_TYPE PLUMBING
J 2
(650 4550);
DISPLAY 1.234043 (650 4550);
PAINT GREEN (650 4550);
DISPLAY INVISIBLE (650 4550);
FORCEPROP 1 LAST HDL_TAP TRUE
J 2
(325 4475);
DISPLAY 1.234043 (325 4475);
PAINT GREEN (325 4475);
DISPLAY INVISIBLE (325 4475);
FORCEPROP 1 LAST PATH I14
J 2
(650 4600);
DISPLAY 0.936170 (650 4600);
PAINT GREEN (650 4600);
DISPLAY INVISIBLE (650 4600);
FORCEADD TAP..6
(-3250 3000);
FORCEPROP 3 LASTPIN (-3200 3000) SIG_NAME M_D_ECC<4>
J 0
(-3190 3010);
DISPLAY 0.659574 (-3190 3010);
PAINT MONO (-3190 3010);
DISPLAY INVISIBLE (-3190 3010);
FORCEPROP 1 LASTPIN (-3200 3000) BN 4
J 0
(-3250 3010);
DISPLAY 0.617021 (-3250 3010);
PAINT PINK (-3250 3010);
FORCEPROP 2 LAST CDS_LIB mstr_standard
J 0
(-3250 3000);
DISPLAY 0.787234 (-3250 3000);
PAINT MONO (-3250 3000);
DISPLAY INVISIBLE (-3250 3000);
FORCEPROP 1 LAST BODY_TYPE PLUMBING
J 0
(-3250 2950);
DISPLAY 1.234043 (-3250 2950);
PAINT GREEN (-3250 2950);
DISPLAY INVISIBLE (-3250 2950);
FORCEPROP 1 LAST HDL_TAP TRUE
J 0
(-2925 2875);
DISPLAY 1.234043 (-2925 2875);
PAINT GREEN (-2925 2875);
DISPLAY INVISIBLE (-2925 2875);
FORCEPROP 1 LAST PATH I140
J 0
(-3250 3000);
DISPLAY 0.936170 (-3250 3000);
PAINT GREEN (-3250 3000);
DISPLAY INVISIBLE (-3250 3000);
FORCEADD TAP..6
(-3250 2950);
FORCEPROP 3 LASTPIN (-3200 2950) SIG_NAME M_D_ECC<5>
J 0
(-3190 2960);
DISPLAY 0.659574 (-3190 2960);
PAINT MONO (-3190 2960);
DISPLAY INVISIBLE (-3190 2960);
FORCEPROP 1 LASTPIN (-3200 2950) BN 5
J 0
(-3250 2960);
DISPLAY 0.617021 (-3250 2960);
PAINT PINK (-3250 2960);
FORCEPROP 2 LAST CDS_LIB mstr_standard
J 0
(-3250 2950);
DISPLAY 0.787234 (-3250 2950);
PAINT MONO (-3250 2950);
DISPLAY INVISIBLE (-3250 2950);
FORCEPROP 1 LAST BODY_TYPE PLUMBING
J 0
(-3250 2900);
DISPLAY 1.234043 (-3250 2900);
PAINT GREEN (-3250 2900);
DISPLAY INVISIBLE (-3250 2900);
FORCEPROP 1 LAST HDL_TAP TRUE
J 0
(-2925 2825);
DISPLAY 1.234043 (-2925 2825);
PAINT GREEN (-2925 2825);
DISPLAY INVISIBLE (-2925 2825);
FORCEPROP 1 LAST PATH I141
J 0
(-3250 2950);
DISPLAY 0.936170 (-3250 2950);
PAINT GREEN (-3250 2950);
DISPLAY INVISIBLE (-3250 2950);
FORCEADD TAP..6
(-3250 2900);
FORCEPROP 3 LASTPIN (-3200 2900) SIG_NAME M_D_ECC<2>
J 0
(-3190 2910);
DISPLAY 0.659574 (-3190 2910);
PAINT MONO (-3190 2910);
DISPLAY INVISIBLE (-3190 2910);
FORCEPROP 1 LASTPIN (-3200 2900) BN 2
J 0
(-3250 2910);
DISPLAY 0.617021 (-3250 2910);
PAINT PINK (-3250 2910);
FORCEPROP 2 LAST CDS_LIB mstr_standard
J 0
(-3250 2900);
DISPLAY 0.787234 (-3250 2900);
PAINT MONO (-3250 2900);
DISPLAY INVISIBLE (-3250 2900);
FORCEPROP 1 LAST BODY_TYPE PLUMBING
J 0
(-3250 2850);
DISPLAY 1.234043 (-3250 2850);
PAINT GREEN (-3250 2850);
DISPLAY INVISIBLE (-3250 2850);
FORCEPROP 1 LAST HDL_TAP TRUE
J 0
(-2925 2775);
DISPLAY 1.234043 (-2925 2775);
PAINT GREEN (-2925 2775);
DISPLAY INVISIBLE (-2925 2775);
FORCEPROP 1 LAST PATH I142
J 0
(-3250 2900);
DISPLAY 0.936170 (-3250 2900);
PAINT GREEN (-3250 2900);
DISPLAY INVISIBLE (-3250 2900);
FORCEADD TAP..6
(-3250 2850);
FORCEPROP 3 LASTPIN (-3200 2850) SIG_NAME M_D_ECC<3>
J 0
(-3190 2860);
DISPLAY 0.659574 (-3190 2860);
PAINT MONO (-3190 2860);
DISPLAY INVISIBLE (-3190 2860);
FORCEPROP 1 LASTPIN (-3200 2850) BN 3
J 0
(-3250 2860);
DISPLAY 0.617021 (-3250 2860);
PAINT PINK (-3250 2860);
FORCEPROP 2 LAST CDS_LIB mstr_standard
J 0
(-3250 2850);
DISPLAY 0.787234 (-3250 2850);
PAINT MONO (-3250 2850);
DISPLAY INVISIBLE (-3250 2850);
FORCEPROP 1 LAST BODY_TYPE PLUMBING
J 0
(-3250 2800);
DISPLAY 1.234043 (-3250 2800);
PAINT GREEN (-3250 2800);
DISPLAY INVISIBLE (-3250 2800);
FORCEPROP 1 LAST HDL_TAP TRUE
J 0
(-2925 2725);
DISPLAY 1.234043 (-2925 2725);
PAINT GREEN (-2925 2725);
DISPLAY INVISIBLE (-2925 2725);
FORCEPROP 1 LAST PATH I143
J 0
(-3250 2850);
DISPLAY 0.936170 (-3250 2850);
PAINT GREEN (-3250 2850);
DISPLAY INVISIBLE (-3250 2850);
FORCEADD TAP..6
(-3250 2800);
FORCEPROP 3 LASTPIN (-3200 2800) SIG_NAME M_D_ECC<0>
J 0
(-3190 2810);
DISPLAY 0.659574 (-3190 2810);
PAINT MONO (-3190 2810);
DISPLAY INVISIBLE (-3190 2810);
FORCEPROP 1 LASTPIN (-3200 2800) BN 0
J 0
(-3250 2810);
DISPLAY 0.617021 (-3250 2810);
PAINT PINK (-3250 2810);
FORCEPROP 2 LAST CDS_LIB mstr_standard
J 0
(-3250 2800);
DISPLAY 0.787234 (-3250 2800);
PAINT MONO (-3250 2800);
DISPLAY INVISIBLE (-3250 2800);
FORCEPROP 1 LAST BODY_TYPE PLUMBING
J 0
(-3250 2750);
DISPLAY 1.234043 (-3250 2750);
PAINT GREEN (-3250 2750);
DISPLAY INVISIBLE (-3250 2750);
FORCEPROP 1 LAST HDL_TAP TRUE
J 0
(-2925 2675);
DISPLAY 1.234043 (-2925 2675);
PAINT GREEN (-2925 2675);
DISPLAY INVISIBLE (-2925 2675);
FORCEPROP 1 LAST PATH I144
J 0
(-3250 2800);
DISPLAY 0.936170 (-3250 2800);
PAINT GREEN (-3250 2800);
DISPLAY INVISIBLE (-3250 2800);
FORCEADD TAP..6
(-3250 2750);
FORCEPROP 3 LASTPIN (-3200 2750) SIG_NAME M_D_ECC<1>
J 0
(-3190 2760);
DISPLAY 0.659574 (-3190 2760);
PAINT MONO (-3190 2760);
DISPLAY INVISIBLE (-3190 2760);
FORCEPROP 1 LASTPIN (-3200 2750) BN 1
J 0
(-3250 2760);
DISPLAY 0.617021 (-3250 2760);
PAINT PINK (-3250 2760);
FORCEPROP 2 LAST CDS_LIB mstr_standard
J 0
(-3250 2750);
DISPLAY 0.787234 (-3250 2750);
PAINT MONO (-3250 2750);
DISPLAY INVISIBLE (-3250 2750);
FORCEPROP 1 LAST BODY_TYPE PLUMBING
J 0
(-3250 2700);
DISPLAY 1.234043 (-3250 2700);
PAINT GREEN (-3250 2700);
DISPLAY INVISIBLE (-3250 2700);
FORCEPROP 1 LAST HDL_TAP TRUE
J 0
(-2925 2625);
DISPLAY 1.234043 (-2925 2625);
PAINT GREEN (-2925 2625);
DISPLAY INVISIBLE (-2925 2625);
FORCEPROP 1 LAST PATH I145
J 0
(-3250 2750);
DISPLAY 0.936170 (-3250 2750);
PAINT GREEN (-3250 2750);
DISPLAY INVISIBLE (-3250 2750);
FORCEADD OFFPAGE..1
(-4000 3100);
FORCEPROP 2 LAST $XR1 50 
J 0
(-4341 3100);
DISPLAY 0.638298 (-4341 3100);
PAINT MONO (-4341 3100);
FORCEPROP 2 LAST $XR0 26 
J 0
(-4251 3100);
DISPLAY 0.638298 (-4251 3100);
PAINT MONO (-4251 3100);
FORCEPROP 2 LAST CDS_LIB mstr_standard
J 0
(-4000 3100);
DISPLAY 0.787234 (-4000 3100);
PAINT MONO (-4000 3100);
DISPLAY INVISIBLE (-4000 3100);
FORCEPROP 1 LAST OFFPAGE TRUE
J 0
(-3675 2975);
DISPLAY 0.936170 (-3675 2975);
PAINT GREEN (-3675 2975);
DISPLAY INVISIBLE (-3675 2975);
FORCEPROP 1 LAST COMMENT_BODY TRUE
J 0
(-3875 3000);
DISPLAY 0.936170 (-3875 3000);
PAINT GREEN (-3875 3000);
DISPLAY INVISIBLE (-3875 3000);
FORCEPROP 2 LAST PATH I146
J 0
(-3950 3175);
DISPLAY 0.787234 (-3950 3175);
PAINT MONO (-3950 3175);
DISPLAY INVISIBLE (-3950 3175);
FORCEADD OFFPAGE..1
(-4000 2450);
FORCEPROP 2 LAST $XR1 50 
J 0
(-4341 2450);
DISPLAY 0.638298 (-4341 2450);
PAINT MONO (-4341 2450);
FORCEPROP 2 LAST $XR0 26 
J 0
(-4251 2450);
DISPLAY 0.638298 (-4251 2450);
PAINT MONO (-4251 2450);
FORCEPROP 2 LAST CDS_LIB mstr_standard
J 0
(-4000 2450);
DISPLAY 0.787234 (-4000 2450);
PAINT MONO (-4000 2450);
DISPLAY INVISIBLE (-4000 2450);
FORCEPROP 1 LAST OFFPAGE TRUE
J 0
(-3675 2325);
DISPLAY 0.936170 (-3675 2325);
PAINT GREEN (-3675 2325);
DISPLAY INVISIBLE (-3675 2325);
FORCEPROP 1 LAST COMMENT_BODY TRUE
J 0
(-3875 2350);
DISPLAY 0.936170 (-3875 2350);
PAINT GREEN (-3875 2350);
DISPLAY INVISIBLE (-3875 2350);
FORCEPROP 2 LAST PATH I147
J 0
(-3950 2525);
DISPLAY 0.787234 (-3950 2525);
PAINT MONO (-3950 2525);
DISPLAY INVISIBLE (-3950 2525);
FORCEADD OFFPAGE..5
(-4025 2500);
FORCEPROP 2 LAST $XR1 26 
J 0
(-4339 2500);
DISPLAY 0.638298 (-4339 2500);
PAINT MONO (-4339 2500);
FORCEPROP 2 LAST $XR0 50 
J 0
(-4249 2500);
DISPLAY 0.638298 (-4249 2500);
PAINT MONO (-4249 2500);
FORCEPROP 2 LAST CDS_LIB mstr_standard
J 0
(-4025 2500);
DISPLAY 0.787234 (-4025 2500);
PAINT MONO (-4025 2500);
DISPLAY INVISIBLE (-4025 2500);
FORCEPROP 1 LAST OFFPAGE TRUE
J 0
(-3700 2375);
DISPLAY 1.404255 (-3700 2375);
PAINT GREEN (-3700 2375);
DISPLAY INVISIBLE (-3700 2375);
FORCEPROP 1 LAST COMMENT_BODY TRUE
J 0
(-3925 2425);
DISPLAY 1.404255 (-3925 2425);
PAINT GREEN (-3925 2425);
DISPLAY INVISIBLE (-3925 2425);
FORCEPROP 2 LAST PATH I148
J 0
(-3975 2575);
DISPLAY 0.787234 (-3975 2575);
PAINT MONO (-3975 2575);
DISPLAY INVISIBLE (-3975 2575);
FORCEADD OFFPAGE..1
(-4000 3050);
FORCEPROP 2 LAST $XR5 54 
J 0
(-4701 3050);
DISPLAY 0.638298 (-4701 3050);
PAINT MONO (-4701 3050);
FORCEPROP 2 LAST $XR4 53 
J 0
(-4611 3050);
DISPLAY 0.638298 (-4611 3050);
PAINT MONO (-4611 3050);
FORCEPROP 2 LAST $XR3 52 
J 0
(-4521 3050);
DISPLAY 0.638298 (-4521 3050);
PAINT MONO (-4521 3050);
FORCEPROP 2 LAST $XR2 51 
J 0
(-4431 3050);
DISPLAY 0.638298 (-4431 3050);
PAINT MONO (-4431 3050);
FORCEPROP 2 LAST $XR1 50 
J 0
(-4341 3050);
DISPLAY 0.638298 (-4341 3050);
PAINT MONO (-4341 3050);
FORCEPROP 2 LAST $XR0 21 
J 0
(-4251 3050);
DISPLAY 0.638298 (-4251 3050);
PAINT MONO (-4251 3050);
FORCEPROP 2 LAST CDS_LIB mstr_standard
J 0
(-4000 3050);
DISPLAY 0.787234 (-4000 3050);
PAINT MONO (-4000 3050);
DISPLAY INVISIBLE (-4000 3050);
FORCEPROP 1 LAST OFFPAGE TRUE
J 0
(-3675 2925);
DISPLAY 0.936170 (-3675 2925);
PAINT GREEN (-3675 2925);
DISPLAY INVISIBLE (-3675 2925);
FORCEPROP 1 LAST COMMENT_BODY TRUE
J 0
(-3875 2950);
DISPLAY 0.936170 (-3875 2950);
PAINT GREEN (-3875 2950);
DISPLAY INVISIBLE (-3875 2950);
FORCEPROP 2 LAST PATH I149
J 0
(-3950 3125);
DISPLAY 0.787234 (-3950 3125);
PAINT MONO (-3950 3125);
DISPLAY INVISIBLE (-3950 3125);
FORCEADD TAP..6
R 2
(650 4700);
FORCEPROP 3 LASTPIN (600 4700) SIG_NAME M_D_DQS_DP<12>
J 0
(610 4710);
DISPLAY 0.659574 (610 4710);
PAINT MONO (610 4710);
DISPLAY INVISIBLE (610 4710);
FORCEPROP 1 LASTPIN (600 4700) BN 12
J 2
(650 4710);
DISPLAY 0.617021 (650 4710);
PAINT PINK (650 4710);
FORCEPROP 2 LAST CDS_LIB mstr_standard
J 0
(650 4700);
DISPLAY 0.787234 (650 4700);
PAINT MONO (650 4700);
DISPLAY INVISIBLE (650 4700);
FORCEPROP 1 LAST BODY_TYPE PLUMBING
J 2
(650 4650);
DISPLAY 1.234043 (650 4650);
PAINT GREEN (650 4650);
DISPLAY INVISIBLE (650 4650);
FORCEPROP 1 LAST HDL_TAP TRUE
J 2
(325 4575);
DISPLAY 1.234043 (325 4575);
PAINT GREEN (325 4575);
DISPLAY INVISIBLE (325 4575);
FORCEPROP 1 LAST PATH I15
J 2
(650 4700);
DISPLAY 0.936170 (650 4700);
PAINT GREEN (650 4700);
DISPLAY INVISIBLE (650 4700);
FORCEADD OFFPAGE..6
(-4000 3150);
FORCEPROP 2 LAST $XR1 50 
J 0
(-4339 3150);
DISPLAY 0.638298 (-4339 3150);
PAINT MONO (-4339 3150);
FORCEPROP 2 LAST $XR0 26 
J 0
(-4249 3150);
DISPLAY 0.638298 (-4249 3150);
PAINT MONO (-4249 3150);
FORCEPROP 2 LAST CDS_LIB mstr_standard
J 0
(-4000 3150);
DISPLAY 0.787234 (-4000 3150);
PAINT MONO (-4000 3150);
DISPLAY INVISIBLE (-4000 3150);
FORCEPROP 1 LAST OFFPAGE TRUE
J 0
(-3675 3025);
DISPLAY 0.936170 (-3675 3025);
PAINT GREEN (-3675 3025);
DISPLAY INVISIBLE (-3675 3025);
FORCEPROP 1 LAST COMMENT_BODY TRUE
J 0
(-3900 3075);
DISPLAY 0.936170 (-3900 3075);
PAINT GREEN (-3900 3075);
DISPLAY INVISIBLE (-3900 3075);
FORCEPROP 2 LAST PATH I150
J 0
(-3950 3225);
DISPLAY 0.787234 (-3950 3225);
PAINT MONO (-3950 3225);
DISPLAY INVISIBLE (-3950 3225);
FORCEADD OFFPAGE..1
(-4800 2000);
FORCEPROP 2 LAST $XR1 50 
J 0
(-5141 2000);
DISPLAY 0.638298 (-5141 2000);
PAINT MONO (-5141 2000);
FORCEPROP 2 LAST $XR0 98 
J 0
(-5051 2000);
DISPLAY 0.638298 (-5051 2000);
PAINT MONO (-5051 2000);
FORCEPROP 2 LAST CDS_LIB mstr_standard
J 0
(-4800 2000);
DISPLAY 0.787234 (-4800 2000);
PAINT MONO (-4800 2000);
DISPLAY INVISIBLE (-4800 2000);
FORCEPROP 1 LAST OFFPAGE TRUE
J 0
(-4475 1875);
DISPLAY 0.936170 (-4475 1875);
PAINT GREEN (-4475 1875);
DISPLAY INVISIBLE (-4475 1875);
FORCEPROP 1 LAST COMMENT_BODY TRUE
J 0
(-4675 1900);
DISPLAY 0.936170 (-4675 1900);
PAINT GREEN (-4675 1900);
DISPLAY INVISIBLE (-4675 1900);
FORCEPROP 2 LAST PATH I151
J 0
(-4750 2075);
DISPLAY 0.787234 (-4750 2075);
PAINT MONO (-4750 2075);
DISPLAY INVISIBLE (-4750 2075);
FORCEADD TAP..6
(-3250 3950);
FORCEPROP 3 LASTPIN (-3200 3950) SIG_NAME M_D_CLK_DP<1>
J 0
(-3190 3960);
DISPLAY 0.659574 (-3190 3960);
PAINT MONO (-3190 3960);
DISPLAY INVISIBLE (-3190 3960);
FORCEPROP 1 LASTPIN (-3200 3950) BN 1
J 0
(-3250 3960);
DISPLAY 0.617021 (-3250 3960);
PAINT PINK (-3250 3960);
FORCEPROP 2 LAST CDS_LIB mstr_standard
J 0
(-3250 3950);
DISPLAY 0.787234 (-3250 3950);
PAINT MONO (-3250 3950);
DISPLAY INVISIBLE (-3250 3950);
FORCEPROP 1 LAST BODY_TYPE PLUMBING
J 0
(-3250 3900);
DISPLAY 1.234043 (-3250 3900);
PAINT GREEN (-3250 3900);
DISPLAY INVISIBLE (-3250 3900);
FORCEPROP 1 LAST HDL_TAP TRUE
J 0
(-2925 3825);
DISPLAY 1.234043 (-2925 3825);
PAINT GREEN (-2925 3825);
DISPLAY INVISIBLE (-2925 3825);
FORCEPROP 1 LAST PATH I152
J 0
(-3250 3950);
DISPLAY 0.936170 (-3250 3950);
PAINT GREEN (-3250 3950);
DISPLAY INVISIBLE (-3250 3950);
FORCEADD TAP..6
(-3250 3850);
FORCEPROP 3 LASTPIN (-3200 3850) SIG_NAME M_D_CLK_DP<0>
J 0
(-3190 3860);
DISPLAY 0.659574 (-3190 3860);
PAINT MONO (-3190 3860);
DISPLAY INVISIBLE (-3190 3860);
FORCEPROP 1 LASTPIN (-3200 3850) BN 0
J 0
(-3250 3860);
DISPLAY 0.617021 (-3250 3860);
PAINT PINK (-3250 3860);
FORCEPROP 2 LAST CDS_LIB mstr_standard
J 0
(-3250 3850);
DISPLAY 0.787234 (-3250 3850);
PAINT MONO (-3250 3850);
DISPLAY INVISIBLE (-3250 3850);
FORCEPROP 1 LAST BODY_TYPE PLUMBING
J 0
(-3250 3800);
DISPLAY 1.234043 (-3250 3800);
PAINT GREEN (-3250 3800);
DISPLAY INVISIBLE (-3250 3800);
FORCEPROP 1 LAST HDL_TAP TRUE
J 0
(-2925 3725);
DISPLAY 1.234043 (-2925 3725);
PAINT GREEN (-2925 3725);
DISPLAY INVISIBLE (-2925 3725);
FORCEPROP 1 LAST PATH I153
J 0
(-3250 3850);
DISPLAY 0.936170 (-3250 3850);
PAINT GREEN (-3250 3850);
DISPLAY INVISIBLE (-3250 3850);
FORCEADD TAP..6
(-3450 3900);
FORCEPROP 3 LASTPIN (-3400 3900) SIG_NAME M_D_CLK_DN<1>
J 0
(-3390 3910);
DISPLAY 0.659574 (-3390 3910);
PAINT MONO (-3390 3910);
DISPLAY INVISIBLE (-3390 3910);
FORCEPROP 1 LASTPIN (-3400 3900) BN 1
J 0
(-3450 3910);
DISPLAY 0.617021 (-3450 3910);
PAINT PINK (-3450 3910);
FORCEPROP 2 LAST CDS_LIB mstr_standard
J 0
(-3450 3900);
DISPLAY 0.787234 (-3450 3900);
PAINT MONO (-3450 3900);
DISPLAY INVISIBLE (-3450 3900);
FORCEPROP 1 LAST BODY_TYPE PLUMBING
J 0
(-3450 3850);
DISPLAY 1.234043 (-3450 3850);
PAINT GREEN (-3450 3850);
DISPLAY INVISIBLE (-3450 3850);
FORCEPROP 1 LAST HDL_TAP TRUE
J 0
(-3125 3775);
DISPLAY 1.234043 (-3125 3775);
PAINT GREEN (-3125 3775);
DISPLAY INVISIBLE (-3125 3775);
FORCEPROP 1 LAST PATH I154
J 0
(-3450 3900);
DISPLAY 0.936170 (-3450 3900);
PAINT GREEN (-3450 3900);
DISPLAY INVISIBLE (-3450 3900);
FORCEADD TAP..6
(-3450 3800);
FORCEPROP 3 LASTPIN (-3400 3800) SIG_NAME M_D_CLK_DN<0>
J 0
(-3390 3810);
DISPLAY 0.659574 (-3390 3810);
PAINT MONO (-3390 3810);
DISPLAY INVISIBLE (-3390 3810);
FORCEPROP 1 LASTPIN (-3400 3800) BN 0
J 0
(-3450 3810);
DISPLAY 0.617021 (-3450 3810);
PAINT PINK (-3450 3810);
FORCEPROP 2 LAST CDS_LIB mstr_standard
J 0
(-3450 3800);
DISPLAY 0.787234 (-3450 3800);
PAINT MONO (-3450 3800);
DISPLAY INVISIBLE (-3450 3800);
FORCEPROP 1 LAST BODY_TYPE PLUMBING
J 0
(-3450 3750);
DISPLAY 1.234043 (-3450 3750);
PAINT GREEN (-3450 3750);
DISPLAY INVISIBLE (-3450 3750);
FORCEPROP 1 LAST HDL_TAP TRUE
J 0
(-3125 3675);
DISPLAY 1.234043 (-3125 3675);
PAINT GREEN (-3125 3675);
DISPLAY INVISIBLE (-3125 3675);
FORCEPROP 1 LAST PATH I155
J 0
(-3450 3800);
DISPLAY 0.936170 (-3450 3800);
PAINT GREEN (-3450 3800);
DISPLAY INVISIBLE (-3450 3800);
FORCEADD OFFPAGE..1
(-4000 3950);
FORCEPROP 2 LAST $XR1 50 
J 0
(-4341 3950);
DISPLAY 0.638298 (-4341 3950);
PAINT MONO (-4341 3950);
FORCEPROP 2 LAST $XR0 26 
J 0
(-4251 3950);
DISPLAY 0.638298 (-4251 3950);
PAINT MONO (-4251 3950);
FORCEPROP 2 LAST CDS_LIB mstr_standard
J 0
(-4000 3950);
DISPLAY 0.787234 (-4000 3950);
PAINT MONO (-4000 3950);
DISPLAY INVISIBLE (-4000 3950);
FORCEPROP 1 LAST OFFPAGE TRUE
J 0
(-3675 3825);
DISPLAY 0.936170 (-3675 3825);
PAINT GREEN (-3675 3825);
DISPLAY INVISIBLE (-3675 3825);
FORCEPROP 1 LAST COMMENT_BODY TRUE
J 0
(-3875 3850);
DISPLAY 0.936170 (-3875 3850);
PAINT GREEN (-3875 3850);
DISPLAY INVISIBLE (-3875 3850);
FORCEPROP 2 LAST PATH I156
J 0
(-3950 4025);
DISPLAY 0.787234 (-3950 4025);
PAINT MONO (-3950 4025);
DISPLAY INVISIBLE (-3950 4025);
FORCEADD OFFPAGE..1
(-4000 4000);
FORCEPROP 2 LAST $XR1 50 
J 0
(-4341 4000);
DISPLAY 0.638298 (-4341 4000);
PAINT MONO (-4341 4000);
FORCEPROP 2 LAST $XR0 26 
J 0
(-4251 4000);
DISPLAY 0.638298 (-4251 4000);
PAINT MONO (-4251 4000);
FORCEPROP 2 LAST CDS_LIB mstr_standard
J 0
(-4000 4000);
DISPLAY 0.787234 (-4000 4000);
PAINT MONO (-4000 4000);
DISPLAY INVISIBLE (-4000 4000);
FORCEPROP 1 LAST OFFPAGE TRUE
J 0
(-3675 3875);
DISPLAY 0.936170 (-3675 3875);
PAINT GREEN (-3675 3875);
DISPLAY INVISIBLE (-3675 3875);
FORCEPROP 1 LAST COMMENT_BODY TRUE
J 0
(-3875 3900);
DISPLAY 0.936170 (-3875 3900);
PAINT GREEN (-3875 3900);
DISPLAY INVISIBLE (-3875 3900);
FORCEPROP 2 LAST PATH I157
J 0
(-3950 4075);
DISPLAY 0.787234 (-3950 4075);
PAINT MONO (-3950 4075);
DISPLAY INVISIBLE (-3950 4075);
FORCEADD TAP..6
(-3250 3650);
FORCEPROP 3 LASTPIN (-3200 3650) SIG_NAME M_D_CS_N<3>
J 0
(-3190 3660);
DISPLAY 0.659574 (-3190 3660);
PAINT MONO (-3190 3660);
DISPLAY INVISIBLE (-3190 3660);
FORCEPROP 1 LASTPIN (-3200 3650) BN 3
J 0
(-3250 3660);
DISPLAY 0.617021 (-3250 3660);
PAINT PINK (-3250 3660);
FORCEPROP 2 LAST CDS_LIB mstr_standard
J 0
(-3250 3650);
DISPLAY 0.787234 (-3250 3650);
PAINT MONO (-3250 3650);
DISPLAY INVISIBLE (-3250 3650);
FORCEPROP 1 LAST BODY_TYPE PLUMBING
J 0
(-3250 3600);
DISPLAY 1.234043 (-3250 3600);
PAINT GREEN (-3250 3600);
DISPLAY INVISIBLE (-3250 3600);
FORCEPROP 1 LAST HDL_TAP TRUE
J 0
(-2925 3525);
DISPLAY 1.234043 (-2925 3525);
PAINT GREEN (-2925 3525);
DISPLAY INVISIBLE (-2925 3525);
FORCEPROP 1 LAST PATH I158
J 0
(-3250 3650);
DISPLAY 0.936170 (-3250 3650);
PAINT GREEN (-3250 3650);
DISPLAY INVISIBLE (-3250 3650);
FORCEADD TAP..6
(-3250 3600);
FORCEPROP 3 LASTPIN (-3200 3600) SIG_NAME M_D_CS_N<2>
J 0
(-3190 3610);
DISPLAY 0.659574 (-3190 3610);
PAINT MONO (-3190 3610);
DISPLAY INVISIBLE (-3190 3610);
FORCEPROP 1 LASTPIN (-3200 3600) BN 2
J 0
(-3250 3610);
DISPLAY 0.617021 (-3250 3610);
PAINT PINK (-3250 3610);
FORCEPROP 2 LAST CDS_LIB mstr_standard
J 0
(-3250 3600);
DISPLAY 0.787234 (-3250 3600);
PAINT MONO (-3250 3600);
DISPLAY INVISIBLE (-3250 3600);
FORCEPROP 1 LAST BODY_TYPE PLUMBING
J 0
(-3250 3550);
DISPLAY 1.234043 (-3250 3550);
PAINT GREEN (-3250 3550);
DISPLAY INVISIBLE (-3250 3550);
FORCEPROP 1 LAST HDL_TAP TRUE
J 0
(-2925 3475);
DISPLAY 1.234043 (-2925 3475);
PAINT GREEN (-2925 3475);
DISPLAY INVISIBLE (-2925 3475);
FORCEPROP 1 LAST PATH I159
J 0
(-3250 3600);
DISPLAY 0.936170 (-3250 3600);
PAINT GREEN (-3250 3600);
DISPLAY INVISIBLE (-3250 3600);
FORCEADD PVDDQ_DEF..1
(-1225 2475);
FORCEPROP 3 LASTPIN (-1225 2425) SIG_NAME PVDDQ_DEF\g
J 0
(-1215 2435);
DISPLAY 0.659574 (-1215 2435);
PAINT MONO (-1215 2435);
DISPLAY INVISIBLE (-1215 2435);
FORCEPROP 1 LAST VOLTAGE 1.2V
J 0
(-1270 2432);
DISPLAY 0.340426 (-1270 2432);
PAINT SKYBLUE (-1270 2432);
DISPLAY INVISIBLE (-1270 2432);
FORCEPROP 2 LAST BOM_COST MEM
J 0
(-1225 2480);
PAINT ORANGE (-1225 2480);
DISPLAY INVISIBLE (-1225 2480);
FORCEPROP 2 LAST CDS_LIB mstr_symbols
J 0
(-1225 2475);
PAINT ORANGE (-1225 2475);
DISPLAY INVISIBLE (-1225 2475);
FORCEPROP 1 LAST BODY_TYPE PLUMBING
J 0
(-1270 2432);
DISPLAY 0.340426 (-1270 2432);
PAINT GREEN (-1270 2432);
DISPLAY INVISIBLE (-1270 2432);
FORCEPROP 1 LAST PATH I16
J 0
(-1175 2500);
DISPLAY 0.872340 (-1175 2500);
PAINT AQUA (-1175 2500);
DISPLAY INVISIBLE (-1175 2500);
FORCEPROP 2 LAST ROOM DDR4_CH_B
J 0
(-1225 2575);
DISPLAY 0.787234 (-1225 2575);
PAINT ORANGE (-1225 2575);
DISPLAY INVISIBLE (-1225 2575);
FORCEPROP 1 LAST HDL_POWER PVDDQ_DEF
J 1
(-1225 2525);
DISPLAY 0.872340 (-1225 2525);
PAINT GREEN (-1225 2525);
DISPLAY INVISIBLE (-1225 2525);
FORCEADD TAP..6
(-3250 3550);
FORCEPROP 3 LASTPIN (-3200 3550) SIG_NAME M_D_CS_N<1>
J 0
(-3190 3560);
DISPLAY 0.659574 (-3190 3560);
PAINT MONO (-3190 3560);
DISPLAY INVISIBLE (-3190 3560);
FORCEPROP 1 LASTPIN (-3200 3550) BN 1
J 0
(-3250 3560);
DISPLAY 0.617021 (-3250 3560);
PAINT PINK (-3250 3560);
FORCEPROP 2 LAST CDS_LIB mstr_standard
J 0
(-3250 3550);
DISPLAY 0.787234 (-3250 3550);
PAINT MONO (-3250 3550);
DISPLAY INVISIBLE (-3250 3550);
FORCEPROP 1 LAST BODY_TYPE PLUMBING
J 0
(-3250 3500);
DISPLAY 1.234043 (-3250 3500);
PAINT GREEN (-3250 3500);
DISPLAY INVISIBLE (-3250 3500);
FORCEPROP 1 LAST HDL_TAP TRUE
J 0
(-2925 3425);
DISPLAY 1.234043 (-2925 3425);
PAINT GREEN (-2925 3425);
DISPLAY INVISIBLE (-2925 3425);
FORCEPROP 1 LAST PATH I160
J 0
(-3250 3550);
DISPLAY 0.936170 (-3250 3550);
PAINT GREEN (-3250 3550);
DISPLAY INVISIBLE (-3250 3550);
FORCEADD TAP..6
(-3250 3500);
FORCEPROP 3 LASTPIN (-3200 3500) SIG_NAME M_D_CS_N<0>
J 0
(-3190 3510);
DISPLAY 0.659574 (-3190 3510);
PAINT MONO (-3190 3510);
DISPLAY INVISIBLE (-3190 3510);
FORCEPROP 1 LASTPIN (-3200 3500) BN 0
J 0
(-3250 3510);
DISPLAY 0.617021 (-3250 3510);
PAINT PINK (-3250 3510);
FORCEPROP 2 LAST CDS_LIB mstr_standard
J 0
(-3250 3500);
DISPLAY 0.787234 (-3250 3500);
PAINT MONO (-3250 3500);
DISPLAY INVISIBLE (-3250 3500);
FORCEPROP 1 LAST BODY_TYPE PLUMBING
J 0
(-3250 3450);
DISPLAY 1.234043 (-3250 3450);
PAINT GREEN (-3250 3450);
DISPLAY INVISIBLE (-3250 3450);
FORCEPROP 1 LAST HDL_TAP TRUE
J 0
(-2925 3375);
DISPLAY 1.234043 (-2925 3375);
PAINT GREEN (-2925 3375);
DISPLAY INVISIBLE (-2925 3375);
FORCEPROP 1 LAST PATH I161
J 0
(-3250 3500);
DISPLAY 0.936170 (-3250 3500);
PAINT GREEN (-3250 3500);
DISPLAY INVISIBLE (-3250 3500);
FORCEADD TAP..6
(-3250 3400);
FORCEPROP 3 LASTPIN (-3200 3400) SIG_NAME M_D_CKE<1>
J 0
(-3190 3410);
DISPLAY 0.659574 (-3190 3410);
PAINT MONO (-3190 3410);
DISPLAY INVISIBLE (-3190 3410);
FORCEPROP 1 LASTPIN (-3200 3400) BN 1
J 0
(-3250 3410);
DISPLAY 0.617021 (-3250 3410);
PAINT PINK (-3250 3410);
FORCEPROP 2 LAST CDS_LIB mstr_standard
J 0
(-3250 3400);
DISPLAY 0.787234 (-3250 3400);
PAINT MONO (-3250 3400);
DISPLAY INVISIBLE (-3250 3400);
FORCEPROP 1 LAST BODY_TYPE PLUMBING
J 0
(-3250 3350);
DISPLAY 1.234043 (-3250 3350);
PAINT GREEN (-3250 3350);
DISPLAY INVISIBLE (-3250 3350);
FORCEPROP 1 LAST HDL_TAP TRUE
J 0
(-2925 3275);
DISPLAY 1.234043 (-2925 3275);
PAINT GREEN (-2925 3275);
DISPLAY INVISIBLE (-2925 3275);
FORCEPROP 1 LAST PATH I162
J 0
(-3250 3400);
DISPLAY 0.936170 (-3250 3400);
PAINT GREEN (-3250 3400);
DISPLAY INVISIBLE (-3250 3400);
FORCEADD TAP..6
(-3250 3350);
FORCEPROP 3 LASTPIN (-3200 3350) SIG_NAME M_D_CKE<0>
J 0
(-3190 3360);
DISPLAY 0.659574 (-3190 3360);
PAINT MONO (-3190 3360);
DISPLAY INVISIBLE (-3190 3360);
FORCEPROP 1 LASTPIN (-3200 3350) BN 0
J 0
(-3250 3360);
DISPLAY 0.617021 (-3250 3360);
PAINT PINK (-3250 3360);
FORCEPROP 2 LAST CDS_LIB mstr_standard
J 0
(-3250 3350);
DISPLAY 0.787234 (-3250 3350);
PAINT MONO (-3250 3350);
DISPLAY INVISIBLE (-3250 3350);
FORCEPROP 1 LAST BODY_TYPE PLUMBING
J 0
(-3250 3300);
DISPLAY 1.234043 (-3250 3300);
PAINT GREEN (-3250 3300);
DISPLAY INVISIBLE (-3250 3300);
FORCEPROP 1 LAST HDL_TAP TRUE
J 0
(-2925 3225);
DISPLAY 1.234043 (-2925 3225);
PAINT GREEN (-2925 3225);
DISPLAY INVISIBLE (-2925 3225);
FORCEPROP 1 LAST PATH I163
J 0
(-3250 3350);
DISPLAY 0.936170 (-3250 3350);
PAINT GREEN (-3250 3350);
DISPLAY INVISIBLE (-3250 3350);
FORCEADD OFFPAGE..1
(-4000 3700);
FORCEPROP 2 LAST $XR1 50 
J 0
(-4341 3700);
DISPLAY 0.638298 (-4341 3700);
PAINT MONO (-4341 3700);
FORCEPROP 2 LAST $XR0 26 
J 0
(-4251 3700);
DISPLAY 0.638298 (-4251 3700);
PAINT MONO (-4251 3700);
FORCEPROP 2 LAST CDS_LIB mstr_standard
J 0
(-4000 3700);
DISPLAY 0.787234 (-4000 3700);
PAINT MONO (-4000 3700);
DISPLAY INVISIBLE (-4000 3700);
FORCEPROP 1 LAST OFFPAGE TRUE
J 0
(-3675 3575);
DISPLAY 0.936170 (-3675 3575);
PAINT GREEN (-3675 3575);
DISPLAY INVISIBLE (-3675 3575);
FORCEPROP 1 LAST COMMENT_BODY TRUE
J 0
(-3875 3600);
DISPLAY 0.936170 (-3875 3600);
PAINT GREEN (-3875 3600);
DISPLAY INVISIBLE (-3875 3600);
FORCEPROP 2 LAST PATH I164
J 0
(-3950 3775);
DISPLAY 0.787234 (-3950 3775);
PAINT MONO (-3950 3775);
DISPLAY INVISIBLE (-3950 3775);
FORCEADD OFFPAGE..1
(-4000 3300);
FORCEPROP 2 LAST $XR1 50 
J 0
(-4341 3300);
DISPLAY 0.638298 (-4341 3300);
PAINT MONO (-4341 3300);
FORCEPROP 2 LAST $XR0 26 
J 0
(-4251 3300);
DISPLAY 0.638298 (-4251 3300);
PAINT MONO (-4251 3300);
FORCEPROP 2 LAST CDS_LIB mstr_standard
J 0
(-4000 3300);
DISPLAY 0.787234 (-4000 3300);
PAINT MONO (-4000 3300);
DISPLAY INVISIBLE (-4000 3300);
FORCEPROP 1 LAST OFFPAGE TRUE
J 0
(-3675 3175);
DISPLAY 0.936170 (-3675 3175);
PAINT GREEN (-3675 3175);
DISPLAY INVISIBLE (-3675 3175);
FORCEPROP 1 LAST COMMENT_BODY TRUE
J 0
(-3875 3200);
DISPLAY 0.936170 (-3875 3200);
PAINT GREEN (-3875 3200);
DISPLAY INVISIBLE (-3875 3200);
FORCEPROP 2 LAST PATH I165
J 0
(-3950 3375);
DISPLAY 0.787234 (-3950 3375);
PAINT MONO (-3950 3375);
DISPLAY INVISIBLE (-3950 3375);
FORCEADD OFFPAGE..1
(-4000 3450);
FORCEPROP 2 LAST $XR1 50 
J 0
(-4341 3450);
DISPLAY 0.638298 (-4341 3450);
PAINT MONO (-4341 3450);
FORCEPROP 2 LAST $XR0 26 
J 0
(-4251 3450);
DISPLAY 0.638298 (-4251 3450);
PAINT MONO (-4251 3450);
FORCEPROP 2 LAST CDS_LIB mstr_standard
J 0
(-4000 3450);
DISPLAY 0.787234 (-4000 3450);
PAINT MONO (-4000 3450);
DISPLAY INVISIBLE (-4000 3450);
FORCEPROP 1 LAST OFFPAGE TRUE
J 0
(-3675 3325);
DISPLAY 0.936170 (-3675 3325);
PAINT GREEN (-3675 3325);
DISPLAY INVISIBLE (-3675 3325);
FORCEPROP 1 LAST COMMENT_BODY TRUE
J 0
(-3875 3350);
DISPLAY 0.936170 (-3875 3350);
PAINT GREEN (-3875 3350);
DISPLAY INVISIBLE (-3875 3350);
FORCEPROP 2 LAST PATH I166
J 0
(-3950 3525);
DISPLAY 0.787234 (-3950 3525);
PAINT MONO (-3950 3525);
DISPLAY INVISIBLE (-3950 3525);
FORCEADD TAP..6
(-3250 3250);
FORCEPROP 3 LASTPIN (-3200 3250) SIG_NAME M_D_ODT<1>
J 0
(-3190 3260);
DISPLAY 0.659574 (-3190 3260);
PAINT MONO (-3190 3260);
DISPLAY INVISIBLE (-3190 3260);
FORCEPROP 1 LASTPIN (-3200 3250) BN 1
J 0
(-3250 3260);
DISPLAY 0.617021 (-3250 3260);
PAINT PINK (-3250 3260);
FORCEPROP 2 LAST CDS_LIB mstr_standard
J 0
(-3250 3250);
DISPLAY 0.787234 (-3250 3250);
PAINT MONO (-3250 3250);
DISPLAY INVISIBLE (-3250 3250);
FORCEPROP 1 LAST BODY_TYPE PLUMBING
J 0
(-3250 3200);
DISPLAY 1.234043 (-3250 3200);
PAINT GREEN (-3250 3200);
DISPLAY INVISIBLE (-3250 3200);
FORCEPROP 1 LAST HDL_TAP TRUE
J 0
(-2925 3125);
DISPLAY 1.234043 (-2925 3125);
PAINT GREEN (-2925 3125);
DISPLAY INVISIBLE (-2925 3125);
FORCEPROP 1 LAST PATH I167
J 0
(-3250 3250);
DISPLAY 0.936170 (-3250 3250);
PAINT GREEN (-3250 3250);
DISPLAY INVISIBLE (-3250 3250);
FORCEADD TAP..6
(-3250 3200);
FORCEPROP 3 LASTPIN (-3200 3200) SIG_NAME M_D_ODT<0>
J 0
(-3190 3210);
DISPLAY 0.659574 (-3190 3210);
PAINT MONO (-3190 3210);
DISPLAY INVISIBLE (-3190 3210);
FORCEPROP 1 LASTPIN (-3200 3200) BN 0
J 0
(-3250 3210);
DISPLAY 0.617021 (-3250 3210);
PAINT PINK (-3250 3210);
FORCEPROP 2 LAST CDS_LIB mstr_standard
J 0
(-3250 3200);
DISPLAY 0.787234 (-3250 3200);
PAINT MONO (-3250 3200);
DISPLAY INVISIBLE (-3250 3200);
FORCEPROP 1 LAST BODY_TYPE PLUMBING
J 0
(-3250 3150);
DISPLAY 1.234043 (-3250 3150);
PAINT GREEN (-3250 3150);
DISPLAY INVISIBLE (-3250 3150);
FORCEPROP 1 LAST HDL_TAP TRUE
J 0
(-2925 3075);
DISPLAY 1.234043 (-2925 3075);
PAINT GREEN (-2925 3075);
DISPLAY INVISIBLE (-2925 3075);
FORCEPROP 1 LAST PATH I168
J 0
(-3250 3200);
DISPLAY 0.936170 (-3250 3200);
PAINT GREEN (-3250 3200);
DISPLAY INVISIBLE (-3250 3200);
FORCEADD SCONN288_H44441004..4
(-50 1950);
FORCEPROP 1 LAST LOCATION J4B1
J 0
(-500 3050);
DISPLAY 0.617021 (-500 3050);
PAINT AQUA (-500 3050);
FORCEPROP 1 LAST PART_NUMBER H44441-004
J 0
(-500 900);
DISPLAY 0.617021 (-500 900);
PAINT BLUE (-500 900);
FORCEPROP 1 LAST MATERIAL SCONN
J 0
(-500 3000);
DISPLAY 0.617021 (-500 3000);
PAINT SKYBLUE (-500 3000);
FORCEPROP 2 LASTPIN (-550 2500) $PN 77
J 2
(-560 2510);
DISPLAY 0.617021 (-560 2510);
PAINT ORANGE (-560 2510);
FORCEPROP 2 LASTPIN (-550 2450) $PN 221
J 2
(-560 2460);
DISPLAY 0.617021 (-560 2460);
PAINT ORANGE (-560 2460);
FORCEPROP 2 LASTPIN (-550 2800) $PN 142
J 2
(-560 2810);
DISPLAY 0.617021 (-560 2810);
PAINT ORANGE (-560 2810);
FORCEPROP 2 LASTPIN (-550 2750) $PN 143
J 2
(-560 2760);
DISPLAY 0.617021 (-560 2760);
PAINT ORANGE (-560 2760);
FORCEPROP 2 LASTPIN (-550 2700) $PN 288
J 2
(-560 2710);
DISPLAY 0.617021 (-560 2710);
PAINT ORANGE (-560 2710);
FORCEPROP 2 LASTPIN (-550 2650) $PN 286
J 2
(-560 2660);
DISPLAY 0.617021 (-560 2660);
PAINT ORANGE (-560 2660);
FORCEPROP 2 LASTPIN (-550 2600) $PN 287
J 2
(-560 2610);
DISPLAY 0.617021 (-560 2610);
PAINT ORANGE (-560 2610);
FORCEPROP 2 LASTPIN (-550 2350) $PN 59
J 2
(-560 2360);
DISPLAY 0.617021 (-560 2360);
PAINT ORANGE (-560 2360);
FORCEPROP 2 LASTPIN (-550 2300) $PN 61
J 2
(-560 2310);
DISPLAY 0.617021 (-560 2310);
PAINT ORANGE (-560 2310);
FORCEPROP 2 LASTPIN (-550 2250) $PN 64
J 2
(-560 2260);
DISPLAY 0.617021 (-560 2260);
PAINT ORANGE (-560 2260);
FORCEPROP 2 LASTPIN (-550 2200) $PN 67
J 2
(-560 2210);
DISPLAY 0.617021 (-560 2210);
PAINT ORANGE (-560 2210);
FORCEPROP 2 LASTPIN (-550 2150) $PN 70
J 2
(-560 2160);
DISPLAY 0.617021 (-560 2160);
PAINT ORANGE (-560 2160);
FORCEPROP 2 LASTPIN (-550 2100) $PN 73
J 2
(-560 2110);
DISPLAY 0.617021 (-560 2110);
PAINT ORANGE (-560 2110);
FORCEPROP 2 LASTPIN (-550 2050) $PN 76
J 2
(-560 2060);
DISPLAY 0.617021 (-560 2060);
PAINT ORANGE (-560 2060);
FORCEPROP 2 LASTPIN (-550 2000) $PN 80
J 2
(-560 2010);
DISPLAY 0.617021 (-560 2010);
PAINT ORANGE (-560 2010);
FORCEPROP 2 LASTPIN (-550 1950) $PN 83
J 2
(-560 1960);
DISPLAY 0.617021 (-560 1960);
PAINT ORANGE (-560 1960);
FORCEPROP 2 LASTPIN (-550 1900) $PN 85
J 2
(-560 1910);
DISPLAY 0.617021 (-560 1910);
PAINT ORANGE (-560 1910);
FORCEPROP 2 LASTPIN (-550 1850) $PN 88
J 2
(-560 1860);
DISPLAY 0.617021 (-560 1860);
PAINT ORANGE (-560 1860);
FORCEPROP 2 LASTPIN (-550 1800) $PN 90
J 2
(-560 1810);
DISPLAY 0.617021 (-560 1810);
PAINT ORANGE (-560 1810);
FORCEPROP 2 LASTPIN (-550 1750) $PN 92
J 2
(-560 1760);
DISPLAY 0.617021 (-560 1760);
PAINT ORANGE (-560 1760);
FORCEPROP 2 LASTPIN (-550 1700) $PN 204
J 2
(-560 1710);
DISPLAY 0.617021 (-560 1710);
PAINT ORANGE (-560 1710);
FORCEPROP 2 LASTPIN (-550 1650) $PN 206
J 2
(-560 1660);
DISPLAY 0.617021 (-560 1660);
PAINT ORANGE (-560 1660);
FORCEPROP 2 LASTPIN (-550 1600) $PN 209
J 2
(-560 1610);
DISPLAY 0.617021 (-560 1610);
PAINT ORANGE (-560 1610);
FORCEPROP 2 LASTPIN (-550 1550) $PN 212
J 2
(-560 1560);
DISPLAY 0.617021 (-560 1560);
PAINT ORANGE (-560 1560);
FORCEPROP 2 LASTPIN (-550 1500) $PN 215
J 2
(-560 1510);
DISPLAY 0.617021 (-560 1510);
PAINT ORANGE (-560 1510);
FORCEPROP 2 LASTPIN (-550 1450) $PN 217
J 2
(-560 1460);
DISPLAY 0.617021 (-560 1460);
PAINT ORANGE (-560 1460);
FORCEPROP 2 LASTPIN (-550 1400) $PN 220
J 2
(-560 1410);
DISPLAY 0.617021 (-560 1410);
PAINT ORANGE (-560 1410);
FORCEPROP 2 LASTPIN (-550 1350) $PN 223
J 2
(-560 1360);
DISPLAY 0.617021 (-560 1360);
PAINT ORANGE (-560 1360);
FORCEPROP 2 LASTPIN (-550 1300) $PN 226
J 2
(-560 1310);
DISPLAY 0.617021 (-560 1310);
PAINT ORANGE (-560 1310);
FORCEPROP 2 LASTPIN (-550 1250) $PN 229
J 2
(-560 1260);
DISPLAY 0.617021 (-560 1260);
PAINT ORANGE (-560 1260);
FORCEPROP 2 LASTPIN (-550 1200) $PN 231
J 2
(-560 1210);
DISPLAY 0.617021 (-560 1210);
PAINT ORANGE (-560 1210);
FORCEPROP 2 LASTPIN (-550 1150) $PN 233
J 2
(-560 1160);
DISPLAY 0.617021 (-560 1160);
PAINT ORANGE (-560 1160);
FORCEPROP 2 LASTPIN (-550 1100) $PN 236
J 2
(-560 1110);
DISPLAY 0.617021 (-560 1110);
PAINT ORANGE (-560 1110);
FORCEPROP 2 LASTPIN (450 2800) $PN 1
J 0
(460 2810);
DISPLAY 0.617021 (460 2810);
PAINT ORANGE (460 2810);
FORCEPROP 2 LASTPIN (450 2750) $PN 145
J 0
(460 2760);
DISPLAY 0.617021 (460 2760);
PAINT ORANGE (460 2760);
FORCEPROP 1 LAST PACK_TYPE PIP
J 0
(-500 3100);
PAINT SKYBLUE (-500 3100);
DISPLAY INVISIBLE (-500 3100);
FORCEPROP 2 LAST BOM_COST MEM
J 0
(-50 1950);
PAINT ORANGE (-50 1950);
DISPLAY INVISIBLE (-50 1950);
FORCEPROP 2 LAST CDS_LIB mstr_sconn
J 0
(-50 1950);
PAINT ORANGE (-50 1950);
DISPLAY INVISIBLE (-50 1950);
FORCEPROP 2 LAST SEC_TYPE PIP
J 0
(-500 3100);
DISPLAY 1.021277 (-500 3100);
PAINT ORANGE (-500 3100);
DISPLAY INVISIBLE (-500 3100);
FORCEPROP 2 LAST SEC 4
J 0
(-500 3100);
DISPLAY 0.680851 (-500 3100);
PAINT MONO (-500 3100);
DISPLAY INVISIBLE (-500 3100);
FORCEPROP 2 LAST CDS_LOCATION J4B1
J 0
(-500 3050);
DISPLAY 0.617021 (-500 3050);
PAINT AQUA (-500 3050);
DISPLAY INVISIBLE (-500 3050);
FORCEPROP 1 LAST PATH I169
J 0
(-50 3000);
PAINT GREEN (-50 3000);
DISPLAY INVISIBLE (-50 3000);
FORCEPROP 2 LAST ROOM DDR4_CH_D
J 0
(-50 1950);
PAINT ORANGE (-50 1950);
DISPLAY INVISIBLE (-50 1950);
FORCEADD PVTT_DEF..1
(-925 2650);
FORCEPROP 3 LASTPIN (-925 2600) SIG_NAME PVTT_DEF\g
J 0
(-915 2610);
DISPLAY 0.659574 (-915 2610);
PAINT MONO (-915 2610);
DISPLAY INVISIBLE (-915 2610);
FORCEPROP 1 LAST VOLTAGE 0.6V
J 0
(-970 2607);
DISPLAY 0.340426 (-970 2607);
PAINT SKYBLUE (-970 2607);
DISPLAY INVISIBLE (-970 2607);
FORCEPROP 2 LAST BOM_COST MEM
J 0
(-925 2655);
PAINT ORANGE (-925 2655);
DISPLAY INVISIBLE (-925 2655);
FORCEPROP 2 LAST CDS_LIB mstr_symbols
J 0
(-925 2650);
PAINT ORANGE (-925 2650);
DISPLAY INVISIBLE (-925 2650);
FORCEPROP 1 LAST BODY_TYPE PLUMBING
J 0
(-970 2607);
DISPLAY 0.340426 (-970 2607);
PAINT GREEN (-970 2607);
DISPLAY INVISIBLE (-970 2607);
FORCEPROP 1 LAST PATH I170
J 0
(-875 2675);
DISPLAY 0.872340 (-875 2675);
PAINT AQUA (-875 2675);
DISPLAY INVISIBLE (-875 2675);
FORCEPROP 2 LAST ROOM DDR4_CH_B
J 0
(-925 2750);
DISPLAY 0.787234 (-925 2750);
PAINT ORANGE (-925 2750);
DISPLAY INVISIBLE (-925 2750);
FORCEPROP 1 LAST HDL_POWER PVTT_DEF
J 1
(-925 2700);
DISPLAY 0.872340 (-925 2700);
PAINT GREEN (-925 2700);
DISPLAY INVISIBLE (-925 2700);
FORCEADD GND..1
R 2
(2500 1150);
FORCEPROP 3 LASTPIN (2500 1200) SIG_NAME GND\g
J 0
(2510 1210);
DISPLAY 0.659574 (2510 1210);
PAINT MONO (2510 1210);
DISPLAY INVISIBLE (2510 1210);
FORCEPROP 1 LAST VOLTAGE 0
J 0
(2500 1150);
PAINT SKYBLUE (2500 1150);
DISPLAY INVISIBLE (2500 1150);
FORCEPROP 1 LAST SIZE 1B
J 2
(2425 1100);
DISPLAY 1.170213 (2425 1100);
PAINT GREEN (2425 1100);
DISPLAY INVISIBLE (2425 1100);
FORCEPROP 2 LAST CDS_LIB mstr_symbols
J 0
(2500 1150);
DISPLAY 0.787234 (2500 1150);
PAINT MONO (2500 1150);
DISPLAY INVISIBLE (2500 1150);
FORCEPROP 2 LAST BOM_COST MEM
J 0
(2500 1155);
PAINT ORANGE (2500 1155);
DISPLAY INVISIBLE (2500 1155);
FORCEPROP 1 LAST BODY_TYPE PLUMBING
J 2
(2545 1107);
DISPLAY 0.340426 (2545 1107);
PAINT GREEN (2545 1107);
DISPLAY INVISIBLE (2545 1107);
FORCEPROP 1 LAST PATH I171
J 2
(2425 1150);
DISPLAY 1.404255 (2425 1150);
PAINT GREEN (2425 1150);
DISPLAY INVISIBLE (2425 1150);
FORCEPROP 2 LAST ROOM DDR4_CH_B
J 0
(2500 1155);
PAINT ORANGE (2500 1155);
DISPLAY INVISIBLE (2500 1155);
FORCEPROP 1 LAST HDL_POWER GND
J 2
(2500 1300);
DISPLAY 0.553191 (2500 1300);
PAINT GREEN (2500 1300);
DISPLAY INVISIBLE (2500 1300);
FORCEADD OFFPAGE..6
(-3850 2150);
FORCEPROP 2 LASTPIN (-3800 2150) SIG_NAME SMB_DDR_DEF_VPP_SDA
J 0
(-3760 2160);
DISPLAY 0.617021 (-3760 2160);
PAINT ORANGE (-3760 2160);
FORCEPROP 2 LAST $XR5 99 
J 0
(-4549 2150);
DISPLAY 0.638298 (-4549 2150);
PAINT MONO (-4549 2150);
FORCEPROP 2 LAST $XR4 54 
J 0
(-4459 2150);
DISPLAY 0.638298 (-4459 2150);
PAINT MONO (-4459 2150);
FORCEPROP 2 LAST $XR3 53 
J 0
(-4369 2150);
DISPLAY 0.638298 (-4369 2150);
PAINT MONO (-4369 2150);
FORCEPROP 2 LAST $XR2 52 
J 0
(-4279 2150);
DISPLAY 0.638298 (-4279 2150);
PAINT MONO (-4279 2150);
FORCEPROP 2 LAST $XR1 51 
J 0
(-4189 2150);
DISPLAY 0.638298 (-4189 2150);
PAINT MONO (-4189 2150);
FORCEPROP 2 LAST $XR0 50 
J 0
(-4099 2150);
DISPLAY 0.638298 (-4099 2150);
PAINT MONO (-4099 2150);
FORCEPROP 2 LAST CDS_LIB mstr_standard
J 0
(-3850 2150);
DISPLAY 0.787234 (-3850 2150);
PAINT MONO (-3850 2150);
DISPLAY INVISIBLE (-3850 2150);
FORCEPROP 1 LAST OFFPAGE TRUE
J 0
(-3525 2025);
DISPLAY 0.936170 (-3525 2025);
PAINT GREEN (-3525 2025);
DISPLAY INVISIBLE (-3525 2025);
FORCEPROP 1 LAST COMMENT_BODY TRUE
J 0
(-3750 2075);
DISPLAY 0.936170 (-3750 2075);
PAINT GREEN (-3750 2075);
DISPLAY INVISIBLE (-3750 2075);
FORCEPROP 2 LAST PATH I174
J 0
(-4150 2200);
DISPLAY 0.787234 (-4150 2200);
PAINT ORANGE (-4150 2200);
DISPLAY INVISIBLE (-4150 2200);
FORCEADD OFFPAGE..1
(-3850 2100);
FORCEPROP 2 LAST $XR5 54 
J 0
(-4551 2100);
DISPLAY 0.638298 (-4551 2100);
PAINT MONO (-4551 2100);
FORCEPROP 2 LAST $XR4 53 
J 0
(-4461 2100);
DISPLAY 0.638298 (-4461 2100);
PAINT MONO (-4461 2100);
FORCEPROP 2 LAST $XR3 52 
J 0
(-4371 2100);
DISPLAY 0.638298 (-4371 2100);
PAINT MONO (-4371 2100);
FORCEPROP 2 LAST $XR2 51 
J 0
(-4281 2100);
DISPLAY 0.638298 (-4281 2100);
PAINT MONO (-4281 2100);
FORCEPROP 2 LAST $XR1 50 
J 0
(-4191 2100);
DISPLAY 0.638298 (-4191 2100);
PAINT MONO (-4191 2100);
FORCEPROP 2 LAST $XR0 99 
J 0
(-4101 2100);
DISPLAY 0.638298 (-4101 2100);
PAINT MONO (-4101 2100);
FORCEPROP 2 LAST CDS_LIB mstr_standard
J 0
(-3850 2100);
DISPLAY 0.787234 (-3850 2100);
PAINT MONO (-3850 2100);
DISPLAY INVISIBLE (-3850 2100);
FORCEPROP 1 LAST OFFPAGE TRUE
J 0
(-3525 1975);
DISPLAY 0.936170 (-3525 1975);
PAINT GREEN (-3525 1975);
DISPLAY INVISIBLE (-3525 1975);
FORCEPROP 1 LAST COMMENT_BODY TRUE
J 0
(-3725 2000);
DISPLAY 0.936170 (-3725 2000);
PAINT GREEN (-3725 2000);
DISPLAY INVISIBLE (-3725 2000);
FORCEPROP 2 LAST PATH I175
J 0
(-4125 2150);
DISPLAY 0.787234 (-4125 2150);
PAINT ORANGE (-4125 2150);
DISPLAY INVISIBLE (-4125 2150);
FORCEADD OFFPAGE..5
(-4225 2850);
FORCEPROP 2 LAST $XR23 94 
J 0
(-4719 2886);
DISPLAY 0.638298 (-4719 2886);
PAINT MONO (-4719 2886);
FORCEPROP 2 LAST $XR22 88 
J 0
(-4629 2886);
DISPLAY 0.638298 (-4629 2886);
PAINT MONO (-4629 2886);
FORCEPROP 2 LAST $XR21 87 
J 0
(-4539 2886);
DISPLAY 0.638298 (-4539 2886);
PAINT MONO (-4539 2886);
FORCEPROP 2 LAST $XR20 86 
J 0
(-4449 2886);
DISPLAY 0.638298 (-4449 2886);
PAINT MONO (-4449 2886);
FORCEPROP 2 LAST $XR19 85 
J 0
(-5259 2814);
DISPLAY 0.638298 (-5259 2814);
PAINT MONO (-5259 2814);
FORCEPROP 2 LAST $XR18 84 
J 0
(-5169 2814);
DISPLAY 0.638298 (-5169 2814);
PAINT MONO (-5169 2814);
FORCEPROP 2 LAST $XR17 83 
J 0
(-5079 2814);
DISPLAY 0.638298 (-5079 2814);
PAINT MONO (-5079 2814);
FORCEPROP 2 LAST $XR16 82 
J 0
(-4989 2814);
DISPLAY 0.638298 (-4989 2814);
PAINT MONO (-4989 2814);
FORCEPROP 2 LAST $XR15 81 
J 0
(-4899 2814);
DISPLAY 0.638298 (-4899 2814);
PAINT MONO (-4899 2814);
FORCEPROP 2 LAST $XR14 80 
J 0
(-4809 2814);
DISPLAY 0.638298 (-4809 2814);
PAINT MONO (-4809 2814);
FORCEPROP 2 LAST $XR13 79 
J 0
(-4719 2814);
DISPLAY 0.638298 (-4719 2814);
PAINT MONO (-4719 2814);
FORCEPROP 2 LAST $XR12 78 
J 0
(-4629 2814);
DISPLAY 0.638298 (-4629 2814);
PAINT MONO (-4629 2814);
FORCEPROP 2 LAST $XR11 77 
J 0
(-4539 2814);
DISPLAY 0.638298 (-4539 2814);
PAINT MONO (-4539 2814);
FORCEPROP 2 LAST $XR10 54 
J 0
(-4449 2814);
DISPLAY 0.638298 (-4449 2814);
PAINT MONO (-4449 2814);
FORCEPROP 2 LAST $XR9 53 
J 0
(-5259 2850);
DISPLAY 0.638298 (-5259 2850);
PAINT MONO (-5259 2850);
FORCEPROP 2 LAST $XR8 52 
J 0
(-5169 2850);
DISPLAY 0.638298 (-5169 2850);
PAINT MONO (-5169 2850);
FORCEPROP 2 LAST $XR7 51 
J 0
(-5079 2850);
DISPLAY 0.638298 (-5079 2850);
PAINT MONO (-5079 2850);
FORCEPROP 2 LAST $XR6 50 
J 0
(-4989 2850);
DISPLAY 0.638298 (-4989 2850);
PAINT MONO (-4989 2850);
FORCEPROP 2 LAST $XR5 48 
J 0
(-4899 2850);
DISPLAY 0.638298 (-4899 2850);
PAINT MONO (-4899 2850);
FORCEPROP 2 LAST $XR4 47 
J 0
(-4809 2850);
DISPLAY 0.638298 (-4809 2850);
PAINT MONO (-4809 2850);
FORCEPROP 2 LAST $XR3 46 
J 0
(-4719 2850);
DISPLAY 0.638298 (-4719 2850);
PAINT MONO (-4719 2850);
FORCEPROP 2 LAST $XR2 45 
J 0
(-4629 2850);
DISPLAY 0.638298 (-4629 2850);
PAINT MONO (-4629 2850);
FORCEPROP 2 LAST $XR1 44 
J 0
(-4539 2850);
DISPLAY 0.638298 (-4539 2850);
PAINT MONO (-4539 2850);
FORCEPROP 2 LAST $XR0 43 
J 0
(-4449 2850);
DISPLAY 0.638298 (-4449 2850);
PAINT MONO (-4449 2850);
FORCEPROP 2 LAST CDS_LIB mstr_standard
J 0
(-4225 2850);
DISPLAY 0.787234 (-4225 2850);
PAINT MONO (-4225 2850);
DISPLAY INVISIBLE (-4225 2850);
FORCEPROP 1 LAST OFFPAGE TRUE
J 0
(-3900 2725);
DISPLAY 1.404255 (-3900 2725);
PAINT GREEN (-3900 2725);
DISPLAY INVISIBLE (-3900 2725);
FORCEPROP 1 LAST COMMENT_BODY TRUE
J 0
(-4125 2775);
DISPLAY 1.404255 (-4125 2775);
PAINT GREEN (-4125 2775);
DISPLAY INVISIBLE (-4125 2775);
FORCEPROP 2 LAST PATH I176
J 0
(-4475 2900);
DISPLAY 0.787234 (-4475 2900);
PAINT ORANGE (-4475 2900);
DISPLAY INVISIBLE (-4475 2900);
FORCEADD GND..1
R 2
(-5100 2100);
FORCEPROP 3 LASTPIN (-5100 2150) SIG_NAME GND\g
J 0
(-5090 2160);
DISPLAY 0.659574 (-5090 2160);
PAINT MONO (-5090 2160);
DISPLAY INVISIBLE (-5090 2160);
FORCEPROP 1 LAST VOLTAGE 0
J 0
(-5100 2100);
PAINT SKYBLUE (-5100 2100);
DISPLAY INVISIBLE (-5100 2100);
FORCEPROP 2 LAST CDS_LIB mstr_symbols
J 0
(-5100 2100);
DISPLAY 0.787234 (-5100 2100);
PAINT MONO (-5100 2100);
DISPLAY INVISIBLE (-5100 2100);
FORCEPROP 1 LAST SIZE 1B
J 2
(-5175 2050);
DISPLAY 1.170213 (-5175 2050);
PAINT GREEN (-5175 2050);
DISPLAY INVISIBLE (-5175 2050);
FORCEPROP 2 LAST BOM_COST MEM
J 0
(-5100 2105);
PAINT ORANGE (-5100 2105);
DISPLAY INVISIBLE (-5100 2105);
FORCEPROP 1 LAST BODY_TYPE PLUMBING
J 2
(-5055 2057);
DISPLAY 0.340426 (-5055 2057);
PAINT GREEN (-5055 2057);
DISPLAY INVISIBLE (-5055 2057);
FORCEPROP 1 LAST PATH I178
J 2
(-5175 2100);
DISPLAY 1.404255 (-5175 2100);
PAINT GREEN (-5175 2100);
DISPLAY INVISIBLE (-5175 2100);
FORCEPROP 2 LAST ROOM DDR4_CH_B
J 0
(-5100 2105);
PAINT ORANGE (-5100 2105);
DISPLAY INVISIBLE (-5100 2105);
FORCEPROP 1 LAST HDL_POWER GND
J 2
(-5100 2250);
DISPLAY 0.553191 (-5100 2250);
PAINT GREEN (-5100 2250);
DISPLAY INVISIBLE (-5100 2250);
FORCEADD CAP_A..1
R 2
(-4650 1800);
FORCEPROP 1 LAST LOCATION C4B12
J 2
(-4700 1900);
DISPLAY 0.617021 (-4700 1900);
PAINT AQUA (-4700 1900);
FORCEPROP 1 LAST PART_NUMBER A36096-045
J 2
(-4700 1650);
DISPLAY 0.617021 (-4700 1650);
PAINT BLUE (-4700 1650);
FORCEPROP 1 LAST VALUE 0.01UF
J 2
(-4700 1850);
DISPLAY 0.617021 (-4700 1850);
PAINT SKYBLUE (-4700 1850);
FORCEPROP 1 LAST TOLERANCE 10%
J 2
(-4700 1750);
DISPLAY 0.617021 (-4700 1750);
PAINT SKYBLUE (-4700 1750);
FORCEPROP 1 LAST VOLTAGE 25V
J 2
(-4700 1800);
DISPLAY 0.617021 (-4700 1800);
PAINT SKYBLUE (-4700 1800);
FORCEPROP 1 LAST MATERIAL X7R
J 2
(-4700 1700);
DISPLAY 0.617021 (-4700 1700);
PAINT SKYBLUE (-4700 1700);
FORCEPROP 1 LAST PACK_TYPE 0402V
J 2
(-4700 1600);
DISPLAY 0.617021 (-4700 1600);
PAINT SKYBLUE (-4700 1600);
FORCEPROP 1 LASTPIN (-4650 1700) $PN 2
J 2
(-4660 1680);
DISPLAY 0.787234 (-4660 1680);
PAINT ORANGE (-4660 1680);
FORCEPROP 1 LASTPIN (-4650 1900) $PN 1
J 2
(-4660 1880);
DISPLAY 0.787234 (-4660 1880);
PAINT ORANGE (-4660 1880);
FORCEPROP 2 LAST CDS_LOCATION C4B12
J 2
(-4700 1900);
DISPLAY 0.617021 (-4700 1900);
PAINT AQUA (-4700 1900);
DISPLAY INVISIBLE (-4700 1900);
FORCEPROP 2 LAST BOM_COST MEM
J 0
(-4650 1800);
PAINT ORANGE (-4650 1800);
DISPLAY INVISIBLE (-4650 1800);
FORCEPROP 2 LAST CDS_LIB dev_discrete
J 0
(-4650 1800);
PAINT ORANGE (-4650 1800);
DISPLAY INVISIBLE (-4650 1800);
FORCEPROP 1 LAST PATH I179
J 2
(-4700 1950);
DISPLAY 0.978723 (-4700 1950);
PAINT WHITE (-4700 1950);
DISPLAY INVISIBLE (-4700 1950);
FORCEPROP 2 LAST ROOM DDR4_CH_B
J 0
(-4650 1800);
PAINT ORANGE (-4650 1800);
DISPLAY INVISIBLE (-4650 1800);
FORCEPROP 2 LAST SEC 1
J 0
(-4700 2000);
PAINT MONO (-4700 2000);
DISPLAY INVISIBLE (-4700 2000);
FORCEPROP 2 LAST SEC_TYPE 0402V
J 0
(-4700 2000);
DISPLAY 1.021277 (-4700 2000);
PAINT ORANGE (-4700 2000);
DISPLAY INVISIBLE (-4700 2000);
FORCEADD GND..1
(-4650 1550);
FORCEPROP 3 LASTPIN (-4650 1600) SIG_NAME GND\g
J 0
(-4640 1610);
DISPLAY 0.659574 (-4640 1610);
PAINT MONO (-4640 1610);
DISPLAY INVISIBLE (-4640 1610);
FORCEPROP 1 LAST VOLTAGE 0
J 0
(-4650 1550);
PAINT SKYBLUE (-4650 1550);
DISPLAY INVISIBLE (-4650 1550);
FORCEPROP 1 LAST SIZE 1B
J 0
(-4575 1500);
DISPLAY 1.787234 (-4575 1500);
PAINT GREEN (-4575 1500);
DISPLAY INVISIBLE (-4575 1500);
FORCEPROP 2 LAST CDS_LIB mstr_symbols
J 0
(-4650 1550);
PAINT ORANGE (-4650 1550);
DISPLAY INVISIBLE (-4650 1550);
FORCEPROP 2 LAST BOM_COST MEM
J 0
(-4650 1555);
PAINT ORANGE (-4650 1555);
DISPLAY INVISIBLE (-4650 1555);
FORCEPROP 1 LAST BODY_TYPE PLUMBING
J 0
(-4695 1507);
DISPLAY 0.340426 (-4695 1507);
PAINT GREEN (-4695 1507);
DISPLAY INVISIBLE (-4695 1507);
FORCEPROP 1 LAST PATH I180
J 0
(-4575 1550);
DISPLAY 1.404255 (-4575 1550);
PAINT GREEN (-4575 1550);
DISPLAY INVISIBLE (-4575 1550);
FORCEPROP 2 LAST ROOM DDR4_CH_B
J 0
(-4650 1555);
PAINT ORANGE (-4650 1555);
DISPLAY INVISIBLE (-4650 1555);
FORCEPROP 1 LAST HDL_POWER GND
J 0
(-4650 1700);
DISPLAY 1.404255 (-4650 1700);
PAINT GREEN (-4650 1700);
DISPLAY INVISIBLE (-4650 1700);
FORCEADD PVPP_DEF..1
(-750 2950);
FORCEPROP 3 LASTPIN (-750 2900) SIG_NAME PVPP_DEF\g
J 0
(-740 2910);
DISPLAY 0.659574 (-740 2910);
PAINT MONO (-740 2910);
DISPLAY INVISIBLE (-740 2910);
FORCEPROP 1 LAST VOLTAGE 2.5V
J 0
(-795 2907);
DISPLAY 0.340426 (-795 2907);
PAINT SKYBLUE (-795 2907);
DISPLAY INVISIBLE (-795 2907);
FORCEPROP 0 LAST BOM_COST MEM
J 0
(-750 3050);
PAINT ORANGE (-750 3050);
DISPLAY INVISIBLE (-750 3050);
FORCEPROP 2 LAST CDS_LIB mstr_symbols
J 0
(-750 2950);
PAINT ORANGE (-750 2950);
DISPLAY INVISIBLE (-750 2950);
FORCEPROP 1 LAST BODY_TYPE PLUMBING
J 0
(-795 2907);
DISPLAY 0.340426 (-795 2907);
PAINT GREEN (-795 2907);
DISPLAY INVISIBLE (-795 2907);
FORCEPROP 1 LAST PATH I181
J 0
(-700 2975);
DISPLAY 0.872340 (-700 2975);
PAINT AQUA (-700 2975);
DISPLAY INVISIBLE (-700 2975);
FORCEPROP 2 LAST ROOM DDR4_CH_B
J 0
(-750 3050);
PAINT ORANGE (-750 3050);
DISPLAY INVISIBLE (-750 3050);
FORCEPROP 1 LAST HDL_POWER PVPP_DEF
J 1
(-750 3000);
DISPLAY 0.872340 (-750 3000);
PAINT GREEN (-750 3000);
DISPLAY INVISIBLE (-750 3000);
FORCEADD PVPP_DEF..1
(-5100 2500);
FORCEPROP 3 LASTPIN (-5100 2450) SIG_NAME PVPP_DEF\g
J 0
(-5090 2460);
DISPLAY 0.659574 (-5090 2460);
PAINT MONO (-5090 2460);
DISPLAY INVISIBLE (-5090 2460);
FORCEPROP 1 LAST VOLTAGE 2.5V
J 0
(-5145 2457);
DISPLAY 0.340426 (-5145 2457);
PAINT SKYBLUE (-5145 2457);
DISPLAY INVISIBLE (-5145 2457);
FORCEPROP 0 LAST BOM_COST MEM
J 0
(-5100 2600);
PAINT ORANGE (-5100 2600);
DISPLAY INVISIBLE (-5100 2600);
FORCEPROP 2 LAST CDS_LIB mstr_symbols
J 0
(-5100 2500);
PAINT ORANGE (-5100 2500);
DISPLAY INVISIBLE (-5100 2500);
FORCEPROP 1 LAST BODY_TYPE PLUMBING
J 0
(-5145 2457);
DISPLAY 0.340426 (-5145 2457);
PAINT GREEN (-5145 2457);
DISPLAY INVISIBLE (-5145 2457);
FORCEPROP 1 LAST PATH I182
J 0
(-5050 2525);
DISPLAY 0.872340 (-5050 2525);
PAINT AQUA (-5050 2525);
DISPLAY INVISIBLE (-5050 2525);
FORCEPROP 2 LAST ROOM DDR4_CH_B
J 0
(-5100 2600);
PAINT ORANGE (-5100 2600);
DISPLAY INVISIBLE (-5100 2600);
FORCEPROP 1 LAST HDL_POWER PVPP_DEF
J 1
(-5100 2550);
DISPLAY 0.872340 (-5100 2550);
PAINT GREEN (-5100 2550);
DISPLAY INVISIBLE (-5100 2550);
FORCEADD OFFPAGE..1
(-3900 1700);
FORCEPROP 2 LAST $XR5 54 
J 0
(-4571 1700);
DISPLAY 0.638298 (-4571 1700);
PAINT MONO (-4571 1700);
FORCEPROP 2 LAST $XR4 53 
J 0
(-4481 1700);
DISPLAY 0.638298 (-4481 1700);
PAINT MONO (-4481 1700);
FORCEPROP 2 LAST $XR3 52 
J 0
(-4391 1700);
DISPLAY 0.638298 (-4391 1700);
PAINT MONO (-4391 1700);
FORCEPROP 2 LAST $XR2 51 
J 0
(-4301 1700);
DISPLAY 0.638298 (-4301 1700);
PAINT MONO (-4301 1700);
FORCEPROP 2 LAST $XR1 50 
J 0
(-4211 1700);
DISPLAY 0.638298 (-4211 1700);
PAINT MONO (-4211 1700);
FORCEPROP 2 LAST $XR0 89 
J 0
(-4121 1700);
DISPLAY 0.638298 (-4121 1700);
PAINT MONO (-4121 1700);
FORCEPROP 2 LAST CDS_LIB mstr_standard
J 0
(-3900 1700);
PAINT ORANGE (-3900 1700);
DISPLAY INVISIBLE (-3900 1700);
FORCEPROP 1 LAST OFFPAGE TRUE
J 0
(-3575 1575);
DISPLAY 0.936170 (-3575 1575);
PAINT GREEN (-3575 1575);
DISPLAY INVISIBLE (-3575 1575);
FORCEPROP 1 LAST COMMENT_BODY TRUE
J 0
(-3775 1600);
DISPLAY 0.936170 (-3775 1600);
PAINT GREEN (-3775 1600);
DISPLAY INVISIBLE (-3775 1600);
FORCEPROP 2 LAST PATH I183
J 0
(-3850 1775);
PAINT ORANGE (-3850 1775);
DISPLAY INVISIBLE (-3850 1775);
FORCEADD P12V_NVDIMM_DEF..1
(650 3025);
FORCEPROP 3 LASTPIN (650 2975) SIG_NAME P12V_NVDIMM_DEF\g
J 0
(660 2985);
DISPLAY 0.659574 (660 2985);
PAINT MONO (660 2985);
DISPLAY INVISIBLE (660 2985);
FORCEPROP 1 LAST VOLTAGE 12.0
J 0
(605 2982);
DISPLAY 0.340426 (605 2982);
PAINT SKYBLUE (605 2982);
DISPLAY INVISIBLE (605 2982);
FORCEPROP 2 LAST CDS_LIB mstr_symbols
J 0
(650 3025);
PAINT ORANGE (650 3025);
DISPLAY INVISIBLE (650 3025);
FORCEPROP 1 LAST BODY_TYPE PLUMBING
J 0
(605 2982);
DISPLAY 0.340426 (605 2982);
PAINT GREEN (605 2982);
DISPLAY INVISIBLE (605 2982);
FORCEPROP 1 LAST PATH I184
J 0
(700 3050);
DISPLAY 0.872340 (700 3050);
PAINT AQUA (700 3050);
DISPLAY INVISIBLE (700 3050);
FORCEPROP 1 LAST HDL_POWER P12V_NVDIMM_DEF
J 1
(650 3075);
DISPLAY 0.872340 (650 3075);
PAINT GREEN (650 3075);
DISPLAY INVISIBLE (650 3075);
FORCEADD TAP..6
R 2
(900 4550);
FORCEPROP 3 LASTPIN (850 4550) SIG_NAME M_D_DQS_DN<11>
J 0
(860 4560);
DISPLAY 0.659574 (860 4560);
PAINT MONO (860 4560);
DISPLAY INVISIBLE (860 4560);
FORCEPROP 1 LASTPIN (850 4550) BN 11
J 2
(900 4560);
DISPLAY 0.617021 (900 4560);
PAINT PINK (900 4560);
FORCEPROP 2 LAST CDS_LIB mstr_standard
J 0
(900 4550);
DISPLAY 0.787234 (900 4550);
PAINT MONO (900 4550);
DISPLAY INVISIBLE (900 4550);
FORCEPROP 1 LAST BODY_TYPE PLUMBING
J 2
(900 4500);
DISPLAY 1.234043 (900 4500);
PAINT GREEN (900 4500);
DISPLAY INVISIBLE (900 4500);
FORCEPROP 1 LAST HDL_TAP TRUE
J 2
(575 4425);
DISPLAY 1.234043 (575 4425);
PAINT GREEN (575 4425);
DISPLAY INVISIBLE (575 4425);
FORCEPROP 1 LAST PATH I19
J 2
(900 4550);
DISPLAY 0.936170 (900 4550);
PAINT GREEN (900 4550);
DISPLAY INVISIBLE (900 4550);
FORCEADD OFFPAGE..3
(1650 5200);
FORCEPROP 2 LAST $XR1 50 
J 0
(1954 5200);
DISPLAY 0.638298 (1954 5200);
PAINT MONO (1954 5200);
FORCEPROP 2 LAST $XR0 26 
J 0
(1864 5200);
DISPLAY 0.638298 (1864 5200);
PAINT MONO (1864 5200);
FORCEPROP 2 LAST CDS_LIB mstr_standard
J 0
(1650 5200);
DISPLAY 0.787234 (1650 5200);
PAINT MONO (1650 5200);
DISPLAY INVISIBLE (1650 5200);
FORCEPROP 1 LAST OFFPAGE TRUE
J 0
(1975 5075);
DISPLAY 0.936170 (1975 5075);
PAINT GREEN (1975 5075);
DISPLAY INVISIBLE (1975 5075);
FORCEPROP 1 LAST COMMENT_BODY TRUE
J 0
(1600 5100);
DISPLAY 0.936170 (1600 5100);
PAINT GREEN (1600 5100);
DISPLAY INVISIBLE (1600 5100);
FORCEPROP 2 LAST PATH I2
J 0
(1850 5275);
DISPLAY 0.787234 (1850 5275);
PAINT MONO (1850 5275);
DISPLAY INVISIBLE (1850 5275);
FORCEADD TAP..6
R 2
(900 4450);
FORCEPROP 3 LASTPIN (850 4450) SIG_NAME M_D_DQS_DN<10>
J 0
(860 4460);
DISPLAY 0.659574 (860 4460);
PAINT MONO (860 4460);
DISPLAY INVISIBLE (860 4460);
FORCEPROP 1 LASTPIN (850 4450) BN 10
J 2
(900 4460);
DISPLAY 0.617021 (900 4460);
PAINT PINK (900 4460);
FORCEPROP 2 LAST CDS_LIB mstr_standard
J 0
(900 4450);
DISPLAY 0.787234 (900 4450);
PAINT MONO (900 4450);
DISPLAY INVISIBLE (900 4450);
FORCEPROP 1 LAST BODY_TYPE PLUMBING
J 2
(900 4400);
DISPLAY 1.234043 (900 4400);
PAINT GREEN (900 4400);
DISPLAY INVISIBLE (900 4400);
FORCEPROP 1 LAST HDL_TAP TRUE
J 2
(575 4325);
DISPLAY 1.234043 (575 4325);
PAINT GREEN (575 4325);
DISPLAY INVISIBLE (575 4325);
FORCEPROP 1 LAST PATH I20
J 2
(900 4450);
DISPLAY 0.936170 (900 4450);
PAINT GREEN (900 4450);
DISPLAY INVISIBLE (900 4450);
FORCEADD TAP..6
R 2
(900 4350);
FORCEPROP 3 LASTPIN (850 4350) SIG_NAME M_D_DQS_DN<9>
J 0
(860 4360);
DISPLAY 0.659574 (860 4360);
PAINT MONO (860 4360);
DISPLAY INVISIBLE (860 4360);
FORCEPROP 1 LASTPIN (850 4350) BN 9
J 2
(900 4360);
DISPLAY 0.617021 (900 4360);
PAINT PINK (900 4360);
FORCEPROP 2 LAST CDS_LIB mstr_standard
J 0
(900 4350);
DISPLAY 0.787234 (900 4350);
PAINT MONO (900 4350);
DISPLAY INVISIBLE (900 4350);
FORCEPROP 1 LAST BODY_TYPE PLUMBING
J 2
(900 4300);
DISPLAY 1.234043 (900 4300);
PAINT GREEN (900 4300);
DISPLAY INVISIBLE (900 4300);
FORCEPROP 1 LAST HDL_TAP TRUE
J 2
(575 4225);
DISPLAY 1.234043 (575 4225);
PAINT GREEN (575 4225);
DISPLAY INVISIBLE (575 4225);
FORCEPROP 1 LAST PATH I21
J 2
(900 4350);
DISPLAY 0.936170 (900 4350);
PAINT GREEN (900 4350);
DISPLAY INVISIBLE (900 4350);
FORCEADD TAP..6
R 2
(900 4250);
FORCEPROP 3 LASTPIN (850 4250) SIG_NAME M_D_DQS_DN<8>
J 0
(860 4260);
DISPLAY 0.659574 (860 4260);
PAINT MONO (860 4260);
DISPLAY INVISIBLE (860 4260);
FORCEPROP 1 LASTPIN (850 4250) BN 8
J 2
(900 4260);
DISPLAY 0.617021 (900 4260);
PAINT PINK (900 4260);
FORCEPROP 2 LAST CDS_LIB mstr_standard
J 0
(900 4250);
DISPLAY 0.787234 (900 4250);
PAINT MONO (900 4250);
DISPLAY INVISIBLE (900 4250);
FORCEPROP 1 LAST BODY_TYPE PLUMBING
J 2
(900 4200);
DISPLAY 1.234043 (900 4200);
PAINT GREEN (900 4200);
DISPLAY INVISIBLE (900 4200);
FORCEPROP 1 LAST HDL_TAP TRUE
J 2
(575 4125);
DISPLAY 1.234043 (575 4125);
PAINT GREEN (575 4125);
DISPLAY INVISIBLE (575 4125);
FORCEPROP 1 LAST PATH I22
J 2
(900 4250);
DISPLAY 0.936170 (900 4250);
PAINT GREEN (900 4250);
DISPLAY INVISIBLE (900 4250);
FORCEADD TAP..6
R 2
(900 4150);
FORCEPROP 3 LASTPIN (850 4150) SIG_NAME M_D_DQS_DN<7>
J 0
(860 4160);
DISPLAY 0.659574 (860 4160);
PAINT MONO (860 4160);
DISPLAY INVISIBLE (860 4160);
FORCEPROP 1 LASTPIN (850 4150) BN 7
J 2
(900 4160);
DISPLAY 0.617021 (900 4160);
PAINT PINK (900 4160);
FORCEPROP 2 LAST CDS_LIB mstr_standard
J 0
(900 4150);
DISPLAY 0.787234 (900 4150);
PAINT MONO (900 4150);
DISPLAY INVISIBLE (900 4150);
FORCEPROP 1 LAST BODY_TYPE PLUMBING
J 2
(900 4100);
DISPLAY 1.234043 (900 4100);
PAINT GREEN (900 4100);
DISPLAY INVISIBLE (900 4100);
FORCEPROP 1 LAST HDL_TAP TRUE
J 2
(575 4025);
DISPLAY 1.234043 (575 4025);
PAINT GREEN (575 4025);
DISPLAY INVISIBLE (575 4025);
FORCEPROP 1 LAST PATH I23
J 2
(900 4150);
DISPLAY 0.936170 (900 4150);
PAINT GREEN (900 4150);
DISPLAY INVISIBLE (900 4150);
FORCEADD TAP..6
R 2
(650 4400);
FORCEPROP 3 LASTPIN (600 4400) SIG_NAME M_D_DQS_DP<9>
J 0
(610 4410);
DISPLAY 0.659574 (610 4410);
PAINT MONO (610 4410);
DISPLAY INVISIBLE (610 4410);
FORCEPROP 1 LASTPIN (600 4400) BN 9
J 2
(650 4410);
DISPLAY 0.617021 (650 4410);
PAINT PINK (650 4410);
FORCEPROP 2 LAST CDS_LIB mstr_standard
J 0
(650 4400);
DISPLAY 0.787234 (650 4400);
PAINT MONO (650 4400);
DISPLAY INVISIBLE (650 4400);
FORCEPROP 1 LAST BODY_TYPE PLUMBING
J 2
(650 4350);
DISPLAY 1.234043 (650 4350);
PAINT GREEN (650 4350);
DISPLAY INVISIBLE (650 4350);
FORCEPROP 1 LAST HDL_TAP TRUE
J 2
(325 4275);
DISPLAY 1.234043 (325 4275);
PAINT GREEN (325 4275);
DISPLAY INVISIBLE (325 4275);
FORCEPROP 1 LAST PATH I24
J 2
(650 4400);
DISPLAY 0.936170 (650 4400);
PAINT GREEN (650 4400);
DISPLAY INVISIBLE (650 4400);
FORCEADD TAP..6
R 2
(650 4500);
FORCEPROP 3 LASTPIN (600 4500) SIG_NAME M_D_DQS_DP<10>
J 0
(610 4510);
DISPLAY 0.659574 (610 4510);
PAINT MONO (610 4510);
DISPLAY INVISIBLE (610 4510);
FORCEPROP 1 LASTPIN (600 4500) BN 10
J 2
(650 4510);
DISPLAY 0.617021 (650 4510);
PAINT PINK (650 4510);
FORCEPROP 2 LAST CDS_LIB mstr_standard
J 0
(650 4500);
DISPLAY 0.787234 (650 4500);
PAINT MONO (650 4500);
DISPLAY INVISIBLE (650 4500);
FORCEPROP 1 LAST BODY_TYPE PLUMBING
J 2
(650 4450);
DISPLAY 1.234043 (650 4450);
PAINT GREEN (650 4450);
DISPLAY INVISIBLE (650 4450);
FORCEPROP 1 LAST HDL_TAP TRUE
J 2
(325 4375);
DISPLAY 1.234043 (325 4375);
PAINT GREEN (325 4375);
DISPLAY INVISIBLE (325 4375);
FORCEPROP 1 LAST PATH I25
J 2
(650 4500);
DISPLAY 0.936170 (650 4500);
PAINT GREEN (650 4500);
DISPLAY INVISIBLE (650 4500);
FORCEADD TAP..6
R 2
(650 4300);
FORCEPROP 3 LASTPIN (600 4300) SIG_NAME M_D_DQS_DP<8>
J 0
(610 4310);
DISPLAY 0.659574 (610 4310);
PAINT MONO (610 4310);
DISPLAY INVISIBLE (610 4310);
FORCEPROP 1 LASTPIN (600 4300) BN 8
J 2
(650 4310);
DISPLAY 0.617021 (650 4310);
PAINT PINK (650 4310);
FORCEPROP 2 LAST CDS_LIB mstr_standard
J 0
(650 4300);
DISPLAY 0.787234 (650 4300);
PAINT MONO (650 4300);
DISPLAY INVISIBLE (650 4300);
FORCEPROP 1 LAST BODY_TYPE PLUMBING
J 2
(650 4250);
DISPLAY 1.234043 (650 4250);
PAINT GREEN (650 4250);
DISPLAY INVISIBLE (650 4250);
FORCEPROP 1 LAST HDL_TAP TRUE
J 2
(325 4175);
DISPLAY 1.234043 (325 4175);
PAINT GREEN (325 4175);
DISPLAY INVISIBLE (325 4175);
FORCEPROP 1 LAST PATH I26
J 2
(650 4300);
DISPLAY 0.936170 (650 4300);
PAINT GREEN (650 4300);
DISPLAY INVISIBLE (650 4300);
FORCEADD TAP..6
R 2
(650 4100);
FORCEPROP 3 LASTPIN (600 4100) SIG_NAME M_D_DQS_DP<6>
J 0
(610 4110);
DISPLAY 0.659574 (610 4110);
PAINT MONO (610 4110);
DISPLAY INVISIBLE (610 4110);
FORCEPROP 1 LASTPIN (600 4100) BN 6
J 2
(650 4110);
DISPLAY 0.617021 (650 4110);
PAINT PINK (650 4110);
FORCEPROP 2 LAST CDS_LIB mstr_standard
J 0
(650 4100);
DISPLAY 0.787234 (650 4100);
PAINT MONO (650 4100);
DISPLAY INVISIBLE (650 4100);
FORCEPROP 1 LAST BODY_TYPE PLUMBING
J 2
(650 4050);
DISPLAY 1.234043 (650 4050);
PAINT GREEN (650 4050);
DISPLAY INVISIBLE (650 4050);
FORCEPROP 1 LAST HDL_TAP TRUE
J 2
(325 3975);
DISPLAY 1.234043 (325 3975);
PAINT GREEN (325 3975);
DISPLAY INVISIBLE (325 3975);
FORCEPROP 1 LAST PATH I27
J 2
(650 4100);
DISPLAY 0.936170 (650 4100);
PAINT GREEN (650 4100);
DISPLAY INVISIBLE (650 4100);
FORCEADD TAP..6
R 2
(650 4200);
FORCEPROP 3 LASTPIN (600 4200) SIG_NAME M_D_DQS_DP<7>
J 0
(610 4210);
DISPLAY 0.659574 (610 4210);
PAINT MONO (610 4210);
DISPLAY INVISIBLE (610 4210);
FORCEPROP 1 LASTPIN (600 4200) BN 7
J 2
(650 4210);
DISPLAY 0.617021 (650 4210);
PAINT PINK (650 4210);
FORCEPROP 2 LAST CDS_LIB mstr_standard
J 0
(650 4200);
DISPLAY 0.787234 (650 4200);
PAINT MONO (650 4200);
DISPLAY INVISIBLE (650 4200);
FORCEPROP 1 LAST BODY_TYPE PLUMBING
J 2
(650 4150);
DISPLAY 1.234043 (650 4150);
PAINT GREEN (650 4150);
DISPLAY INVISIBLE (650 4150);
FORCEPROP 1 LAST HDL_TAP TRUE
J 2
(325 4075);
DISPLAY 1.234043 (325 4075);
PAINT GREEN (325 4075);
DISPLAY INVISIBLE (325 4075);
FORCEPROP 1 LAST PATH I28
J 2
(650 4200);
DISPLAY 0.936170 (650 4200);
PAINT GREEN (650 4200);
DISPLAY INVISIBLE (650 4200);
FORCEADD TAP..6
R 2
(900 4050);
FORCEPROP 3 LASTPIN (850 4050) SIG_NAME M_D_DQS_DN<6>
J 0
(860 4060);
DISPLAY 0.659574 (860 4060);
PAINT MONO (860 4060);
DISPLAY INVISIBLE (860 4060);
FORCEPROP 1 LASTPIN (850 4050) BN 6
J 2
(900 4060);
DISPLAY 0.617021 (900 4060);
PAINT PINK (900 4060);
FORCEPROP 2 LAST CDS_LIB mstr_standard
J 0
(900 4050);
DISPLAY 0.787234 (900 4050);
PAINT MONO (900 4050);
DISPLAY INVISIBLE (900 4050);
FORCEPROP 1 LAST BODY_TYPE PLUMBING
J 2
(900 4000);
DISPLAY 1.234043 (900 4000);
PAINT GREEN (900 4000);
DISPLAY INVISIBLE (900 4000);
FORCEPROP 1 LAST HDL_TAP TRUE
J 2
(575 3925);
DISPLAY 1.234043 (575 3925);
PAINT GREEN (575 3925);
DISPLAY INVISIBLE (575 3925);
FORCEPROP 1 LAST PATH I29
J 2
(900 4050);
DISPLAY 0.936170 (900 4050);
PAINT GREEN (900 4050);
DISPLAY INVISIBLE (900 4050);
FORCEADD TAP..6
R 2
(900 5150);
FORCEPROP 3 LASTPIN (850 5150) SIG_NAME M_D_DQS_DN<17>
J 0
(860 5160);
DISPLAY 0.659574 (860 5160);
PAINT MONO (860 5160);
DISPLAY INVISIBLE (860 5160);
FORCEPROP 1 LASTPIN (850 5150) BN 17
J 2
(900 5160);
DISPLAY 0.617021 (900 5160);
PAINT PINK (900 5160);
FORCEPROP 2 LAST CDS_LIB mstr_standard
J 2
(900 5150);
DISPLAY 0.787234 (900 5150);
PAINT MONO (900 5150);
DISPLAY INVISIBLE (900 5150);
FORCEPROP 1 LAST BODY_TYPE PLUMBING
J 2
(900 5100);
DISPLAY 1.234043 (900 5100);
PAINT GREEN (900 5100);
DISPLAY INVISIBLE (900 5100);
FORCEPROP 1 LAST HDL_TAP TRUE
J 2
(575 5025);
DISPLAY 1.234043 (575 5025);
PAINT GREEN (575 5025);
DISPLAY INVISIBLE (575 5025);
FORCEPROP 1 LAST PATH I3
J 2
(900 5150);
DISPLAY 0.936170 (900 5150);
PAINT GREEN (900 5150);
DISPLAY INVISIBLE (900 5150);
FORCEADD TAP..6
R 2
(900 3950);
FORCEPROP 3 LASTPIN (850 3950) SIG_NAME M_D_DQS_DN<5>
J 0
(860 3960);
DISPLAY 0.659574 (860 3960);
PAINT MONO (860 3960);
DISPLAY INVISIBLE (860 3960);
FORCEPROP 1 LASTPIN (850 3950) BN 5
J 2
(900 3960);
DISPLAY 0.617021 (900 3960);
PAINT PINK (900 3960);
FORCEPROP 2 LAST CDS_LIB mstr_standard
J 0
(900 3950);
DISPLAY 0.787234 (900 3950);
PAINT MONO (900 3950);
DISPLAY INVISIBLE (900 3950);
FORCEPROP 1 LAST BODY_TYPE PLUMBING
J 2
(900 3900);
DISPLAY 1.234043 (900 3900);
PAINT GREEN (900 3900);
DISPLAY INVISIBLE (900 3900);
FORCEPROP 1 LAST HDL_TAP TRUE
J 2
(575 3825);
DISPLAY 1.234043 (575 3825);
PAINT GREEN (575 3825);
DISPLAY INVISIBLE (575 3825);
FORCEPROP 1 LAST PATH I30
J 2
(900 3950);
DISPLAY 0.936170 (900 3950);
PAINT GREEN (900 3950);
DISPLAY INVISIBLE (900 3950);
FORCEADD TAP..6
R 2
(900 3850);
FORCEPROP 3 LASTPIN (850 3850) SIG_NAME M_D_DQS_DN<4>
J 0
(860 3860);
DISPLAY 0.659574 (860 3860);
PAINT MONO (860 3860);
DISPLAY INVISIBLE (860 3860);
FORCEPROP 1 LASTPIN (850 3850) BN 4
J 2
(900 3860);
DISPLAY 0.617021 (900 3860);
PAINT PINK (900 3860);
FORCEPROP 2 LAST CDS_LIB mstr_standard
J 0
(900 3850);
DISPLAY 0.787234 (900 3850);
PAINT MONO (900 3850);
DISPLAY INVISIBLE (900 3850);
FORCEPROP 1 LAST BODY_TYPE PLUMBING
J 2
(900 3800);
DISPLAY 1.234043 (900 3800);
PAINT GREEN (900 3800);
DISPLAY INVISIBLE (900 3800);
FORCEPROP 1 LAST HDL_TAP TRUE
J 2
(575 3725);
DISPLAY 1.234043 (575 3725);
PAINT GREEN (575 3725);
DISPLAY INVISIBLE (575 3725);
FORCEPROP 1 LAST PATH I31
J 2
(900 3850);
DISPLAY 0.936170 (900 3850);
PAINT GREEN (900 3850);
DISPLAY INVISIBLE (900 3850);
FORCEADD TAP..6
R 2
(900 3750);
FORCEPROP 3 LASTPIN (850 3750) SIG_NAME M_D_DQS_DN<3>
J 0
(860 3760);
DISPLAY 0.659574 (860 3760);
PAINT MONO (860 3760);
DISPLAY INVISIBLE (860 3760);
FORCEPROP 1 LASTPIN (850 3750) BN 3
J 2
(900 3760);
DISPLAY 0.617021 (900 3760);
PAINT PINK (900 3760);
FORCEPROP 2 LAST CDS_LIB mstr_standard
J 0
(900 3750);
DISPLAY 0.787234 (900 3750);
PAINT MONO (900 3750);
DISPLAY INVISIBLE (900 3750);
FORCEPROP 1 LAST BODY_TYPE PLUMBING
J 2
(900 3700);
DISPLAY 1.234043 (900 3700);
PAINT GREEN (900 3700);
DISPLAY INVISIBLE (900 3700);
FORCEPROP 1 LAST HDL_TAP TRUE
J 2
(575 3625);
DISPLAY 1.234043 (575 3625);
PAINT GREEN (575 3625);
DISPLAY INVISIBLE (575 3625);
FORCEPROP 1 LAST PATH I32
J 2
(900 3750);
DISPLAY 0.936170 (900 3750);
PAINT GREEN (900 3750);
DISPLAY INVISIBLE (900 3750);
FORCEADD TAP..6
R 2
(900 3650);
FORCEPROP 3 LASTPIN (850 3650) SIG_NAME M_D_DQS_DN<2>
J 0
(860 3660);
DISPLAY 0.659574 (860 3660);
PAINT MONO (860 3660);
DISPLAY INVISIBLE (860 3660);
FORCEPROP 1 LASTPIN (850 3650) BN 2
J 2
(900 3660);
DISPLAY 0.617021 (900 3660);
PAINT PINK (900 3660);
FORCEPROP 2 LAST CDS_LIB mstr_standard
J 0
(900 3650);
DISPLAY 0.787234 (900 3650);
PAINT MONO (900 3650);
DISPLAY INVISIBLE (900 3650);
FORCEPROP 1 LAST BODY_TYPE PLUMBING
J 2
(900 3600);
DISPLAY 1.234043 (900 3600);
PAINT GREEN (900 3600);
DISPLAY INVISIBLE (900 3600);
FORCEPROP 1 LAST HDL_TAP TRUE
J 2
(575 3525);
DISPLAY 1.234043 (575 3525);
PAINT GREEN (575 3525);
DISPLAY INVISIBLE (575 3525);
FORCEPROP 1 LAST PATH I33
J 2
(900 3650);
DISPLAY 0.936170 (900 3650);
PAINT GREEN (900 3650);
DISPLAY INVISIBLE (900 3650);
FORCEADD TAP..6
R 2
(650 3900);
FORCEPROP 3 LASTPIN (600 3900) SIG_NAME M_D_DQS_DP<4>
J 0
(610 3910);
DISPLAY 0.659574 (610 3910);
PAINT MONO (610 3910);
DISPLAY INVISIBLE (610 3910);
FORCEPROP 1 LASTPIN (600 3900) BN 4
J 2
(650 3910);
DISPLAY 0.617021 (650 3910);
PAINT PINK (650 3910);
FORCEPROP 2 LAST CDS_LIB mstr_standard
J 0
(650 3900);
DISPLAY 0.787234 (650 3900);
PAINT MONO (650 3900);
DISPLAY INVISIBLE (650 3900);
FORCEPROP 1 LAST BODY_TYPE PLUMBING
J 2
(650 3850);
DISPLAY 1.234043 (650 3850);
PAINT GREEN (650 3850);
DISPLAY INVISIBLE (650 3850);
FORCEPROP 1 LAST HDL_TAP TRUE
J 2
(325 3775);
DISPLAY 1.234043 (325 3775);
PAINT GREEN (325 3775);
DISPLAY INVISIBLE (325 3775);
FORCEPROP 1 LAST PATH I34
J 2
(650 3900);
DISPLAY 0.936170 (650 3900);
PAINT GREEN (650 3900);
DISPLAY INVISIBLE (650 3900);
FORCEADD TAP..6
R 2
(650 4000);
FORCEPROP 3 LASTPIN (600 4000) SIG_NAME M_D_DQS_DP<5>
J 0
(610 4010);
DISPLAY 0.659574 (610 4010);
PAINT MONO (610 4010);
DISPLAY INVISIBLE (610 4010);
FORCEPROP 1 LASTPIN (600 4000) BN 5
J 2
(650 4010);
DISPLAY 0.617021 (650 4010);
PAINT PINK (650 4010);
FORCEPROP 2 LAST CDS_LIB mstr_standard
J 0
(650 4000);
DISPLAY 0.787234 (650 4000);
PAINT MONO (650 4000);
DISPLAY INVISIBLE (650 4000);
FORCEPROP 1 LAST BODY_TYPE PLUMBING
J 2
(650 3950);
DISPLAY 1.234043 (650 3950);
PAINT GREEN (650 3950);
DISPLAY INVISIBLE (650 3950);
FORCEPROP 1 LAST HDL_TAP TRUE
J 2
(325 3875);
DISPLAY 1.234043 (325 3875);
PAINT GREEN (325 3875);
DISPLAY INVISIBLE (325 3875);
FORCEPROP 1 LAST PATH I35
J 2
(650 4000);
DISPLAY 0.936170 (650 4000);
PAINT GREEN (650 4000);
DISPLAY INVISIBLE (650 4000);
FORCEADD TAP..6
R 2
(650 3800);
FORCEPROP 3 LASTPIN (600 3800) SIG_NAME M_D_DQS_DP<3>
J 0
(610 3810);
DISPLAY 0.659574 (610 3810);
PAINT MONO (610 3810);
DISPLAY INVISIBLE (610 3810);
FORCEPROP 1 LASTPIN (600 3800) BN 3
J 2
(650 3810);
DISPLAY 0.617021 (650 3810);
PAINT PINK (650 3810);
FORCEPROP 2 LAST CDS_LIB mstr_standard
J 0
(650 3800);
DISPLAY 0.787234 (650 3800);
PAINT MONO (650 3800);
DISPLAY INVISIBLE (650 3800);
FORCEPROP 1 LAST BODY_TYPE PLUMBING
J 2
(650 3750);
DISPLAY 1.234043 (650 3750);
PAINT GREEN (650 3750);
DISPLAY INVISIBLE (650 3750);
FORCEPROP 1 LAST HDL_TAP TRUE
J 2
(325 3675);
DISPLAY 1.234043 (325 3675);
PAINT GREEN (325 3675);
DISPLAY INVISIBLE (325 3675);
FORCEPROP 1 LAST PATH I36
J 2
(650 3800);
DISPLAY 0.936170 (650 3800);
PAINT GREEN (650 3800);
DISPLAY INVISIBLE (650 3800);
FORCEADD TAP..6
R 2
(650 3700);
FORCEPROP 3 LASTPIN (600 3700) SIG_NAME M_D_DQS_DP<2>
J 0
(610 3710);
DISPLAY 0.659574 (610 3710);
PAINT MONO (610 3710);
DISPLAY INVISIBLE (610 3710);
FORCEPROP 1 LASTPIN (600 3700) BN 2
J 2
(650 3710);
DISPLAY 0.617021 (650 3710);
PAINT PINK (650 3710);
FORCEPROP 2 LAST CDS_LIB mstr_standard
J 0
(650 3700);
DISPLAY 0.787234 (650 3700);
PAINT MONO (650 3700);
DISPLAY INVISIBLE (650 3700);
FORCEPROP 1 LAST BODY_TYPE PLUMBING
J 2
(650 3650);
DISPLAY 1.234043 (650 3650);
PAINT GREEN (650 3650);
DISPLAY INVISIBLE (650 3650);
FORCEPROP 1 LAST HDL_TAP TRUE
J 2
(325 3575);
DISPLAY 1.234043 (325 3575);
PAINT GREEN (325 3575);
DISPLAY INVISIBLE (325 3575);
FORCEPROP 1 LAST PATH I37
J 2
(650 3700);
DISPLAY 0.936170 (650 3700);
PAINT GREEN (650 3700);
DISPLAY INVISIBLE (650 3700);
FORCEADD TAP..6
R 2
(650 3600);
FORCEPROP 3 LASTPIN (600 3600) SIG_NAME M_D_DQS_DP<1>
J 0
(610 3610);
DISPLAY 0.659574 (610 3610);
PAINT MONO (610 3610);
DISPLAY INVISIBLE (610 3610);
FORCEPROP 1 LASTPIN (600 3600) BN 1
J 2
(650 3610);
DISPLAY 0.617021 (650 3610);
PAINT PINK (650 3610);
FORCEPROP 2 LAST CDS_LIB mstr_standard
J 0
(650 3600);
DISPLAY 0.787234 (650 3600);
PAINT MONO (650 3600);
DISPLAY INVISIBLE (650 3600);
FORCEPROP 1 LAST BODY_TYPE PLUMBING
J 2
(650 3550);
DISPLAY 1.234043 (650 3550);
PAINT GREEN (650 3550);
DISPLAY INVISIBLE (650 3550);
FORCEPROP 1 LAST HDL_TAP TRUE
J 2
(325 3475);
DISPLAY 1.234043 (325 3475);
PAINT GREEN (325 3475);
DISPLAY INVISIBLE (325 3475);
FORCEPROP 1 LAST PATH I38
J 2
(650 3600);
DISPLAY 0.936170 (650 3600);
PAINT GREEN (650 3600);
DISPLAY INVISIBLE (650 3600);
FORCEADD TAP..6
R 2
(900 3450);
FORCEPROP 3 LASTPIN (850 3450) SIG_NAME M_D_DQS_DN<0>
J 0
(860 3460);
DISPLAY 0.659574 (860 3460);
PAINT MONO (860 3460);
DISPLAY INVISIBLE (860 3460);
FORCEPROP 1 LASTPIN (850 3450) BN 0
J 2
(900 3460);
DISPLAY 0.617021 (900 3460);
PAINT PINK (900 3460);
FORCEPROP 2 LAST CDS_LIB mstr_standard
J 0
(900 3450);
DISPLAY 0.787234 (900 3450);
PAINT MONO (900 3450);
DISPLAY INVISIBLE (900 3450);
FORCEPROP 1 LAST BODY_TYPE PLUMBING
J 2
(900 3400);
DISPLAY 1.234043 (900 3400);
PAINT GREEN (900 3400);
DISPLAY INVISIBLE (900 3400);
FORCEPROP 1 LAST HDL_TAP TRUE
J 2
(575 3325);
DISPLAY 1.234043 (575 3325);
PAINT GREEN (575 3325);
DISPLAY INVISIBLE (575 3325);
FORCEPROP 1 LAST PATH I39
J 2
(900 3450);
DISPLAY 0.936170 (900 3450);
PAINT GREEN (900 3450);
DISPLAY INVISIBLE (900 3450);
FORCEADD TAP..6
R 2
(650 5200);
FORCEPROP 3 LASTPIN (600 5200) SIG_NAME M_D_DQS_DP<17>
J 0
(610 5210);
DISPLAY 0.659574 (610 5210);
PAINT MONO (610 5210);
DISPLAY INVISIBLE (610 5210);
FORCEPROP 1 LASTPIN (600 5200) BN 17
J 2
(650 5210);
DISPLAY 0.617021 (650 5210);
PAINT PINK (650 5210);
FORCEPROP 2 LAST CDS_LIB mstr_standard
J 2
(650 5200);
DISPLAY 0.787234 (650 5200);
PAINT MONO (650 5200);
DISPLAY INVISIBLE (650 5200);
FORCEPROP 1 LAST BODY_TYPE PLUMBING
J 2
(650 5150);
DISPLAY 1.234043 (650 5150);
PAINT GREEN (650 5150);
DISPLAY INVISIBLE (650 5150);
FORCEPROP 1 LAST HDL_TAP TRUE
J 2
(325 5075);
DISPLAY 1.234043 (325 5075);
PAINT GREEN (325 5075);
DISPLAY INVISIBLE (325 5075);
FORCEPROP 1 LAST PATH I4
J 2
(650 5200);
DISPLAY 0.936170 (650 5200);
PAINT GREEN (650 5200);
DISPLAY INVISIBLE (650 5200);
FORCEADD TAP..6
R 2
(900 3550);
FORCEPROP 3 LASTPIN (850 3550) SIG_NAME M_D_DQS_DN<1>
J 0
(860 3560);
DISPLAY 0.659574 (860 3560);
PAINT MONO (860 3560);
DISPLAY INVISIBLE (860 3560);
FORCEPROP 1 LASTPIN (850 3550) BN 1
J 2
(900 3560);
DISPLAY 0.617021 (900 3560);
PAINT PINK (900 3560);
FORCEPROP 2 LAST CDS_LIB mstr_standard
J 0
(900 3550);
DISPLAY 0.787234 (900 3550);
PAINT MONO (900 3550);
DISPLAY INVISIBLE (900 3550);
FORCEPROP 1 LAST BODY_TYPE PLUMBING
J 2
(900 3500);
DISPLAY 1.234043 (900 3500);
PAINT GREEN (900 3500);
DISPLAY INVISIBLE (900 3500);
FORCEPROP 1 LAST HDL_TAP TRUE
J 2
(575 3425);
DISPLAY 1.234043 (575 3425);
PAINT GREEN (575 3425);
DISPLAY INVISIBLE (575 3425);
FORCEPROP 1 LAST PATH I40
J 2
(900 3550);
DISPLAY 0.936170 (900 3550);
PAINT GREEN (900 3550);
DISPLAY INVISIBLE (900 3550);
FORCEADD TAP..6
R 2
(650 3500);
FORCEPROP 3 LASTPIN (600 3500) SIG_NAME M_D_DQS_DP<0>
J 0
(610 3510);
DISPLAY 0.659574 (610 3510);
PAINT MONO (610 3510);
DISPLAY INVISIBLE (610 3510);
FORCEPROP 1 LASTPIN (600 3500) BN 0
J 2
(650 3510);
DISPLAY 0.617021 (650 3510);
PAINT PINK (650 3510);
FORCEPROP 2 LAST CDS_LIB mstr_standard
J 0
(650 3500);
DISPLAY 0.787234 (650 3500);
PAINT MONO (650 3500);
DISPLAY INVISIBLE (650 3500);
FORCEPROP 1 LAST BODY_TYPE PLUMBING
J 2
(650 3450);
DISPLAY 1.234043 (650 3450);
PAINT GREEN (650 3450);
DISPLAY INVISIBLE (650 3450);
FORCEPROP 1 LAST HDL_TAP TRUE
J 2
(325 3375);
DISPLAY 1.234043 (325 3375);
PAINT GREEN (325 3375);
DISPLAY INVISIBLE (325 3375);
FORCEPROP 1 LAST PATH I41
J 2
(650 3500);
DISPLAY 0.936170 (650 3500);
PAINT GREEN (650 3500);
DISPLAY INVISIBLE (650 3500);
FORCEADD SCONN288_H44441004..3
(1800 2450);
FORCEPROP 1 LAST PART_NUMBER H44441-004
J 0
(1350 1100);
DISPLAY 0.617021 (1350 1100);
PAINT BLUE (1350 1100);
FORCEPROP 1 LAST MATERIAL SCONN
J 0
(1350 3800);
DISPLAY 0.617021 (1350 3800);
PAINT SKYBLUE (1350 3800);
FORCEPROP 2 LASTPIN (1300 3600) $PN 2
J 2
(1290 3610);
DISPLAY 0.617021 (1290 3610);
PAINT ORANGE (1290 3610);
FORCEPROP 2 LASTPIN (1300 3550) $PN 4
J 2
(1290 3560);
DISPLAY 0.617021 (1290 3560);
PAINT ORANGE (1290 3560);
FORCEPROP 2 LASTPIN (1300 3500) $PN 6
J 2
(1290 3510);
DISPLAY 0.617021 (1290 3510);
PAINT ORANGE (1290 3510);
FORCEPROP 2 LASTPIN (1300 3450) $PN 9
J 2
(1290 3460);
DISPLAY 0.617021 (1290 3460);
PAINT ORANGE (1290 3460);
FORCEPROP 2 LASTPIN (1300 3400) $PN 11
J 2
(1290 3410);
DISPLAY 0.617021 (1290 3410);
PAINT ORANGE (1290 3410);
FORCEPROP 2 LASTPIN (1300 3350) $PN 13
J 2
(1290 3360);
DISPLAY 0.617021 (1290 3360);
PAINT ORANGE (1290 3360);
FORCEPROP 2 LASTPIN (1300 3300) $PN 15
J 2
(1290 3310);
DISPLAY 0.617021 (1290 3310);
PAINT ORANGE (1290 3310);
FORCEPROP 2 LASTPIN (1300 3250) $PN 17
J 2
(1290 3260);
DISPLAY 0.617021 (1290 3260);
PAINT ORANGE (1290 3260);
FORCEPROP 2 LASTPIN (1300 3200) $PN 20
J 2
(1290 3210);
DISPLAY 0.617021 (1290 3210);
PAINT ORANGE (1290 3210);
FORCEPROP 2 LASTPIN (1300 3150) $PN 22
J 2
(1290 3160);
DISPLAY 0.617021 (1290 3160);
PAINT ORANGE (1290 3160);
FORCEPROP 2 LASTPIN (1300 3100) $PN 24
J 2
(1290 3110);
DISPLAY 0.617021 (1290 3110);
PAINT ORANGE (1290 3110);
FORCEPROP 2 LASTPIN (1300 3050) $PN 26
J 2
(1290 3060);
DISPLAY 0.617021 (1290 3060);
PAINT ORANGE (1290 3060);
FORCEPROP 2 LASTPIN (1300 3000) $PN 28
J 2
(1290 3010);
DISPLAY 0.617021 (1290 3010);
PAINT ORANGE (1290 3010);
FORCEPROP 2 LASTPIN (1300 2950) $PN 31
J 2
(1290 2960);
DISPLAY 0.617021 (1290 2960);
PAINT ORANGE (1290 2960);
FORCEPROP 2 LASTPIN (1300 2900) $PN 33
J 2
(1290 2910);
DISPLAY 0.617021 (1290 2910);
PAINT ORANGE (1290 2910);
FORCEPROP 2 LASTPIN (1300 2850) $PN 35
J 2
(1290 2860);
DISPLAY 0.617021 (1290 2860);
PAINT ORANGE (1290 2860);
FORCEPROP 2 LASTPIN (1300 2800) $PN 37
J 2
(1290 2810);
DISPLAY 0.617021 (1290 2810);
PAINT ORANGE (1290 2810);
FORCEPROP 2 LASTPIN (1300 2750) $PN 39
J 2
(1290 2760);
DISPLAY 0.617021 (1290 2760);
PAINT ORANGE (1290 2760);
FORCEPROP 2 LASTPIN (1300 2700) $PN 42
J 2
(1290 2710);
DISPLAY 0.617021 (1290 2710);
PAINT ORANGE (1290 2710);
FORCEPROP 2 LASTPIN (1300 2650) $PN 44
J 2
(1290 2660);
DISPLAY 0.617021 (1290 2660);
PAINT ORANGE (1290 2660);
FORCEPROP 2 LASTPIN (1300 2600) $PN 46
J 2
(1290 2610);
DISPLAY 0.617021 (1290 2610);
PAINT ORANGE (1290 2610);
FORCEPROP 2 LASTPIN (1300 2550) $PN 48
J 2
(1290 2560);
DISPLAY 0.617021 (1290 2560);
PAINT ORANGE (1290 2560);
FORCEPROP 2 LASTPIN (1300 2500) $PN 50
J 2
(1290 2510);
DISPLAY 0.617021 (1290 2510);
PAINT ORANGE (1290 2510);
FORCEPROP 2 LASTPIN (1300 2450) $PN 53
J 2
(1290 2460);
DISPLAY 0.617021 (1290 2460);
PAINT ORANGE (1290 2460);
FORCEPROP 2 LASTPIN (1300 2400) $PN 55
J 2
(1290 2410);
DISPLAY 0.617021 (1290 2410);
PAINT ORANGE (1290 2410);
FORCEPROP 2 LASTPIN (1300 2350) $PN 57
J 2
(1290 2360);
DISPLAY 0.617021 (1290 2360);
PAINT ORANGE (1290 2360);
FORCEPROP 2 LASTPIN (1300 2300) $PN 94
J 2
(1290 2310);
DISPLAY 0.617021 (1290 2310);
PAINT ORANGE (1290 2310);
FORCEPROP 2 LASTPIN (1300 2250) $PN 96
J 2
(1290 2260);
DISPLAY 0.617021 (1290 2260);
PAINT ORANGE (1290 2260);
FORCEPROP 2 LASTPIN (1300 2200) $PN 98
J 2
(1290 2210);
DISPLAY 0.617021 (1290 2210);
PAINT ORANGE (1290 2210);
FORCEPROP 2 LASTPIN (1300 2150) $PN 101
J 2
(1290 2160);
DISPLAY 0.617021 (1290 2160);
PAINT ORANGE (1290 2160);
FORCEPROP 2 LASTPIN (1300 2100) $PN 103
J 2
(1290 2110);
DISPLAY 0.617021 (1290 2110);
PAINT ORANGE (1290 2110);
FORCEPROP 2 LASTPIN (1300 2050) $PN 105
J 2
(1290 2060);
DISPLAY 0.617021 (1290 2060);
PAINT ORANGE (1290 2060);
FORCEPROP 2 LASTPIN (1300 2000) $PN 107
J 2
(1290 2010);
DISPLAY 0.617021 (1290 2010);
PAINT ORANGE (1290 2010);
FORCEPROP 2 LASTPIN (1300 1900) $PN 112
J 2
(1290 1910);
DISPLAY 0.617021 (1290 1910);
PAINT ORANGE (1290 1910);
FORCEPROP 2 LASTPIN (1300 1850) $PN 114
J 2
(1290 1860);
DISPLAY 0.617021 (1290 1860);
PAINT ORANGE (1290 1860);
FORCEPROP 2 LASTPIN (1300 1800) $PN 116
J 2
(1290 1810);
DISPLAY 0.617021 (1290 1810);
PAINT ORANGE (1290 1810);
FORCEPROP 2 LASTPIN (1300 1750) $PN 118
J 2
(1290 1760);
DISPLAY 0.617021 (1290 1760);
PAINT ORANGE (1290 1760);
FORCEPROP 2 LASTPIN (1300 1700) $PN 120
J 2
(1290 1710);
DISPLAY 0.617021 (1290 1710);
PAINT ORANGE (1290 1710);
FORCEPROP 2 LASTPIN (1300 1650) $PN 123
J 2
(1290 1660);
DISPLAY 0.617021 (1290 1660);
PAINT ORANGE (1290 1660);
FORCEPROP 2 LASTPIN (1300 1600) $PN 125
J 2
(1290 1610);
DISPLAY 0.617021 (1290 1610);
PAINT ORANGE (1290 1610);
FORCEPROP 2 LASTPIN (1300 1550) $PN 127
J 2
(1290 1560);
DISPLAY 0.617021 (1290 1560);
PAINT ORANGE (1290 1560);
FORCEPROP 2 LASTPIN (1300 1450) $PN 131
J 2
(1290 1460);
DISPLAY 0.617021 (1290 1460);
PAINT ORANGE (1290 1460);
FORCEPROP 2 LASTPIN (1300 1400) $PN 134
J 2
(1290 1410);
DISPLAY 0.617021 (1290 1410);
PAINT ORANGE (1290 1410);
FORCEPROP 2 LASTPIN (1300 1350) $PN 136
J 2
(1290 1360);
DISPLAY 0.617021 (1290 1360);
PAINT ORANGE (1290 1360);
FORCEPROP 2 LASTPIN (1300 1300) $PN 138
J 2
(1290 1310);
DISPLAY 0.617021 (1290 1310);
PAINT ORANGE (1290 1310);
FORCEPROP 2 LASTPIN (2300 3600) $PN 147
J 0
(2310 3610);
DISPLAY 0.617021 (2310 3610);
PAINT ORANGE (2310 3610);
FORCEPROP 2 LASTPIN (2300 3550) $PN 149
J 0
(2310 3560);
DISPLAY 0.617021 (2310 3560);
PAINT ORANGE (2310 3560);
FORCEPROP 2 LASTPIN (2300 3500) $PN 151
J 0
(2310 3510);
DISPLAY 0.617021 (2310 3510);
PAINT ORANGE (2310 3510);
FORCEPROP 2 LASTPIN (2300 3450) $PN 154
J 0
(2310 3460);
DISPLAY 0.617021 (2310 3460);
PAINT ORANGE (2310 3460);
FORCEPROP 2 LASTPIN (2300 3400) $PN 156
J 0
(2310 3410);
DISPLAY 0.617021 (2310 3410);
PAINT ORANGE (2310 3410);
FORCEPROP 2 LASTPIN (2300 3350) $PN 158
J 0
(2310 3360);
DISPLAY 0.617021 (2310 3360);
PAINT ORANGE (2310 3360);
FORCEPROP 2 LASTPIN (2300 3300) $PN 160
J 0
(2310 3310);
DISPLAY 0.617021 (2310 3310);
PAINT ORANGE (2310 3310);
FORCEPROP 2 LASTPIN (2300 3250) $PN 162
J 0
(2310 3260);
DISPLAY 0.617021 (2310 3260);
PAINT ORANGE (2310 3260);
FORCEPROP 2 LASTPIN (2300 3200) $PN 165
J 0
(2310 3210);
DISPLAY 0.617021 (2310 3210);
PAINT ORANGE (2310 3210);
FORCEPROP 2 LASTPIN (2300 3150) $PN 167
J 0
(2310 3160);
DISPLAY 0.617021 (2310 3160);
PAINT ORANGE (2310 3160);
FORCEPROP 2 LASTPIN (2300 3100) $PN 169
J 0
(2310 3110);
DISPLAY 0.617021 (2310 3110);
PAINT ORANGE (2310 3110);
FORCEPROP 2 LASTPIN (2300 3050) $PN 171
J 0
(2310 3060);
DISPLAY 0.617021 (2310 3060);
PAINT ORANGE (2310 3060);
FORCEPROP 2 LASTPIN (2300 3000) $PN 173
J 0
(2310 3010);
DISPLAY 0.617021 (2310 3010);
PAINT ORANGE (2310 3010);
FORCEPROP 2 LASTPIN (2300 2950) $PN 176
J 0
(2310 2960);
DISPLAY 0.617021 (2310 2960);
PAINT ORANGE (2310 2960);
FORCEPROP 2 LASTPIN (2300 2900) $PN 178
J 0
(2310 2910);
DISPLAY 0.617021 (2310 2910);
PAINT ORANGE (2310 2910);
FORCEPROP 2 LASTPIN (2300 2850) $PN 180
J 0
(2310 2860);
DISPLAY 0.617021 (2310 2860);
PAINT ORANGE (2310 2860);
FORCEPROP 2 LASTPIN (2300 2800) $PN 182
J 0
(2310 2810);
DISPLAY 0.617021 (2310 2810);
PAINT ORANGE (2310 2810);
FORCEPROP 2 LASTPIN (2300 2750) $PN 184
J 0
(2310 2760);
DISPLAY 0.617021 (2310 2760);
PAINT ORANGE (2310 2760);
FORCEPROP 2 LASTPIN (2300 2700) $PN 187
J 0
(2310 2710);
DISPLAY 0.617021 (2310 2710);
PAINT ORANGE (2310 2710);
FORCEPROP 2 LASTPIN (2300 2650) $PN 189
J 0
(2310 2660);
DISPLAY 0.617021 (2310 2660);
PAINT ORANGE (2310 2660);
FORCEPROP 2 LASTPIN (2300 2600) $PN 191
J 0
(2310 2610);
DISPLAY 0.617021 (2310 2610);
PAINT ORANGE (2310 2610);
FORCEPROP 2 LASTPIN (2300 2550) $PN 193
J 0
(2310 2560);
DISPLAY 0.617021 (2310 2560);
PAINT ORANGE (2310 2560);
FORCEPROP 2 LASTPIN (2300 2500) $PN 195
J 0
(2310 2510);
DISPLAY 0.617021 (2310 2510);
PAINT ORANGE (2310 2510);
FORCEPROP 2 LASTPIN (2300 2450) $PN 198
J 0
(2310 2460);
DISPLAY 0.617021 (2310 2460);
PAINT ORANGE (2310 2460);
FORCEPROP 2 LASTPIN (2300 2400) $PN 200
J 0
(2310 2410);
DISPLAY 0.617021 (2310 2410);
PAINT ORANGE (2310 2410);
FORCEPROP 2 LASTPIN (2300 2350) $PN 202
J 0
(2310 2360);
DISPLAY 0.617021 (2310 2360);
PAINT ORANGE (2310 2360);
FORCEPROP 2 LASTPIN (2300 2300) $PN 239
J 0
(2310 2310);
DISPLAY 0.617021 (2310 2310);
PAINT ORANGE (2310 2310);
FORCEPROP 2 LASTPIN (2300 2250) $PN 241
J 0
(2310 2260);
DISPLAY 0.617021 (2310 2260);
PAINT ORANGE (2310 2260);
FORCEPROP 2 LASTPIN (2300 2200) $PN 243
J 0
(2310 2210);
DISPLAY 0.617021 (2310 2210);
PAINT ORANGE (2310 2210);
FORCEPROP 2 LASTPIN (2300 2150) $PN 246
J 0
(2310 2160);
DISPLAY 0.617021 (2310 2160);
PAINT ORANGE (2310 2160);
FORCEPROP 2 LASTPIN (2300 2100) $PN 248
J 0
(2310 2110);
DISPLAY 0.617021 (2310 2110);
PAINT ORANGE (2310 2110);
FORCEPROP 2 LASTPIN (2300 2050) $PN 250
J 0
(2310 2060);
DISPLAY 0.617021 (2310 2060);
PAINT ORANGE (2310 2060);
FORCEPROP 2 LASTPIN (2300 2000) $PN 252
J 0
(2310 2010);
DISPLAY 0.617021 (2310 2010);
PAINT ORANGE (2310 2010);
FORCEPROP 2 LASTPIN (2300 1950) $PN 254
J 0
(2310 1960);
DISPLAY 0.617021 (2310 1960);
PAINT ORANGE (2310 1960);
FORCEPROP 2 LASTPIN (2300 1900) $PN 257
J 0
(2310 1910);
DISPLAY 0.617021 (2310 1910);
PAINT ORANGE (2310 1910);
FORCEPROP 2 LASTPIN (2300 1850) $PN 259
J 0
(2310 1860);
DISPLAY 0.617021 (2310 1860);
PAINT ORANGE (2310 1860);
FORCEPROP 2 LASTPIN (2300 1800) $PN 261
J 0
(2310 1810);
DISPLAY 0.617021 (2310 1810);
PAINT ORANGE (2310 1810);
FORCEPROP 2 LASTPIN (2300 1750) $PN 263
J 0
(2310 1760);
DISPLAY 0.617021 (2310 1760);
PAINT ORANGE (2310 1760);
FORCEPROP 2 LASTPIN (2300 1700) $PN 265
J 0
(2310 1710);
DISPLAY 0.617021 (2310 1710);
PAINT ORANGE (2310 1710);
FORCEPROP 2 LASTPIN (2300 1650) $PN 268
J 0
(2310 1660);
DISPLAY 0.617021 (2310 1660);
PAINT ORANGE (2310 1660);
FORCEPROP 2 LASTPIN (2300 1600) $PN 270
J 0
(2310 1610);
DISPLAY 0.617021 (2310 1610);
PAINT ORANGE (2310 1610);
FORCEPROP 2 LASTPIN (2300 1550) $PN 272
J 0
(2310 1560);
DISPLAY 0.617021 (2310 1560);
PAINT ORANGE (2310 1560);
FORCEPROP 2 LASTPIN (2300 1500) $PN 274
J 0
(2310 1510);
DISPLAY 0.617021 (2310 1510);
PAINT ORANGE (2310 1510);
FORCEPROP 2 LASTPIN (2300 1450) $PN 276
J 0
(2310 1460);
DISPLAY 0.617021 (2310 1460);
PAINT ORANGE (2310 1460);
FORCEPROP 2 LASTPIN (2300 1400) $PN 279
J 0
(2310 1410);
DISPLAY 0.617021 (2310 1410);
PAINT ORANGE (2310 1410);
FORCEPROP 2 LASTPIN (2300 1350) $PN 281
J 0
(2310 1360);
DISPLAY 0.617021 (2310 1360);
PAINT ORANGE (2310 1360);
FORCEPROP 2 LASTPIN (2300 1300) $PN 283
J 0
(2310 1310);
DISPLAY 0.617021 (2310 1310);
PAINT ORANGE (2310 1310);
FORCEPROP 1 LAST LOCATION J4B1
J 0
(1350 3850);
DISPLAY 0.617021 (1350 3850);
PAINT AQUA (1350 3850);
FORCEPROP 2 LASTPIN (1300 1950) $PN 109
J 2
(1290 1960);
DISPLAY 0.617021 (1290 1960);
PAINT ORANGE (1290 1960);
FORCEPROP 2 LASTPIN (1300 1500) $PN 129
J 2
(1290 1510);
DISPLAY 0.617021 (1290 1510);
PAINT ORANGE (1290 1510);
FORCEPROP 1 LAST PACK_TYPE PIP
J 0
(1350 3900);
PAINT SKYBLUE (1350 3900);
DISPLAY INVISIBLE (1350 3900);
FORCEPROP 2 LAST BOM_COST MEM
J 0
(1800 2450);
PAINT ORANGE (1800 2450);
DISPLAY INVISIBLE (1800 2450);
FORCEPROP 2 LAST CDS_LIB mstr_sconn
J 0
(1800 2450);
PAINT ORANGE (1800 2450);
DISPLAY INVISIBLE (1800 2450);
FORCEPROP 2 LAST SEC_TYPE PIP
J 0
(1350 3900);
DISPLAY 1.021277 (1350 3900);
PAINT ORANGE (1350 3900);
DISPLAY INVISIBLE (1350 3900);
FORCEPROP 2 LAST SEC 3
J 0
(1350 3900);
DISPLAY 0.680851 (1350 3900);
PAINT MONO (1350 3900);
DISPLAY INVISIBLE (1350 3900);
FORCEPROP 2 LAST CDS_LOCATION J4B1
J 0
(1350 3850);
DISPLAY 0.617021 (1350 3850);
PAINT AQUA (1350 3850);
DISPLAY INVISIBLE (1350 3850);
FORCEPROP 1 LAST PATH I43
J 0
(1800 3800);
PAINT GREEN (1800 3800);
DISPLAY INVISIBLE (1800 3800);
FORCEPROP 2 LAST ROOM DDR4_CH_D
J 0
(1800 2450);
PAINT ORANGE (1800 2450);
DISPLAY INVISIBLE (1800 2450);
FORCEADD GND..1
R 2
(1100 1150);
FORCEPROP 3 LASTPIN (1100 1200) SIG_NAME GND\g
J 0
(1110 1210);
DISPLAY 0.659574 (1110 1210);
PAINT MONO (1110 1210);
DISPLAY INVISIBLE (1110 1210);
FORCEPROP 1 LAST VOLTAGE 0
J 0
(1100 1150);
PAINT SKYBLUE (1100 1150);
DISPLAY INVISIBLE (1100 1150);
FORCEPROP 1 LAST SIZE 1B
J 2
(1025 1100);
DISPLAY 1.170213 (1025 1100);
PAINT GREEN (1025 1100);
DISPLAY INVISIBLE (1025 1100);
FORCEPROP 2 LAST CDS_LIB mstr_symbols
J 0
(1100 1150);
DISPLAY 0.787234 (1100 1150);
PAINT MONO (1100 1150);
DISPLAY INVISIBLE (1100 1150);
FORCEPROP 2 LAST BOM_COST MEM
J 0
(1100 1155);
PAINT ORANGE (1100 1155);
DISPLAY INVISIBLE (1100 1155);
FORCEPROP 1 LAST BODY_TYPE PLUMBING
J 2
(1145 1107);
DISPLAY 0.340426 (1145 1107);
PAINT GREEN (1145 1107);
DISPLAY INVISIBLE (1145 1107);
FORCEPROP 1 LAST PATH I44
J 2
(1025 1150);
DISPLAY 0.936170 (1025 1150);
PAINT GREEN (1025 1150);
DISPLAY INVISIBLE (1025 1150);
FORCEPROP 2 LAST ROOM DDR4_CH_B
J 0
(1100 1155);
PAINT ORANGE (1100 1155);
DISPLAY INVISIBLE (1100 1155);
FORCEPROP 1 LAST HDL_POWER GND
J 2
(1100 1300);
DISPLAY 0.553191 (1100 1300);
PAINT GREEN (1100 1300);
DISPLAY INVISIBLE (1100 1300);
FORCEADD OFFPAGE..3
(-1200 5200);
FORCEPROP 2 LAST $XR1 50 
J 0
(-896 5200);
DISPLAY 0.638298 (-896 5200);
PAINT MONO (-896 5200);
FORCEPROP 2 LAST $XR0 26 
J 0
(-986 5200);
DISPLAY 0.638298 (-986 5200);
PAINT MONO (-986 5200);
FORCEPROP 2 LAST CDS_LIB mstr_standard
J 0
(-1200 5200);
DISPLAY 0.787234 (-1200 5200);
PAINT MONO (-1200 5200);
DISPLAY INVISIBLE (-1200 5200);
FORCEPROP 1 LAST OFFPAGE TRUE
J 0
(-875 5075);
DISPLAY 0.936170 (-875 5075);
PAINT GREEN (-875 5075);
DISPLAY INVISIBLE (-875 5075);
FORCEPROP 1 LAST COMMENT_BODY TRUE
J 0
(-1250 5100);
DISPLAY 0.936170 (-1250 5100);
PAINT GREEN (-1250 5100);
DISPLAY INVISIBLE (-1250 5100);
FORCEPROP 2 LAST PATH I45
J 0
(-1000 5275);
DISPLAY 0.787234 (-1000 5275);
PAINT MONO (-1000 5275);
DISPLAY INVISIBLE (-1000 5275);
FORCEADD TAP..6
R 2
(-1750 5150);
FORCEPROP 3 LASTPIN (-1800 5150) SIG_NAME M_D_DQ<62>
J 0
(-1790 5160);
DISPLAY 0.659574 (-1790 5160);
PAINT MONO (-1790 5160);
DISPLAY INVISIBLE (-1790 5160);
FORCEPROP 1 LASTPIN (-1800 5150) BN 62
J 2
(-1750 5160);
DISPLAY 0.617021 (-1750 5160);
PAINT PINK (-1750 5160);
FORCEPROP 2 LAST CDS_LIB mstr_standard
J 2
(-1750 5150);
DISPLAY 0.787234 (-1750 5150);
PAINT MONO (-1750 5150);
DISPLAY INVISIBLE (-1750 5150);
FORCEPROP 1 LAST BODY_TYPE PLUMBING
J 2
(-1750 5100);
DISPLAY 1.234043 (-1750 5100);
PAINT GREEN (-1750 5100);
DISPLAY INVISIBLE (-1750 5100);
FORCEPROP 1 LAST HDL_TAP TRUE
J 2
(-2075 5025);
DISPLAY 1.234043 (-2075 5025);
PAINT GREEN (-2075 5025);
DISPLAY INVISIBLE (-2075 5025);
FORCEPROP 1 LAST PATH I46
J 2
(-1750 5150);
DISPLAY 0.936170 (-1750 5150);
PAINT GREEN (-1750 5150);
DISPLAY INVISIBLE (-1750 5150);
FORCEADD TAP..6
R 2
(-1750 5100);
FORCEPROP 3 LASTPIN (-1800 5100) SIG_NAME M_D_DQ<63>
J 0
(-1790 5110);
DISPLAY 0.659574 (-1790 5110);
PAINT MONO (-1790 5110);
DISPLAY INVISIBLE (-1790 5110);
FORCEPROP 1 LASTPIN (-1800 5100) BN 63
J 2
(-1750 5110);
DISPLAY 0.617021 (-1750 5110);
PAINT PINK (-1750 5110);
FORCEPROP 2 LAST CDS_LIB mstr_standard
J 2
(-1750 5100);
DISPLAY 0.787234 (-1750 5100);
PAINT MONO (-1750 5100);
DISPLAY INVISIBLE (-1750 5100);
FORCEPROP 1 LAST BODY_TYPE PLUMBING
J 2
(-1750 5050);
DISPLAY 1.234043 (-1750 5050);
PAINT GREEN (-1750 5050);
DISPLAY INVISIBLE (-1750 5050);
FORCEPROP 1 LAST HDL_TAP TRUE
J 2
(-2075 4975);
DISPLAY 1.234043 (-2075 4975);
PAINT GREEN (-2075 4975);
DISPLAY INVISIBLE (-2075 4975);
FORCEPROP 1 LAST PATH I47
J 2
(-1750 5100);
DISPLAY 0.936170 (-1750 5100);
PAINT GREEN (-1750 5100);
DISPLAY INVISIBLE (-1750 5100);
FORCEADD TAP..6
R 2
(-1750 5000);
FORCEPROP 3 LASTPIN (-1800 5000) SIG_NAME M_D_DQ<61>
J 0
(-1790 5010);
DISPLAY 0.659574 (-1790 5010);
PAINT MONO (-1790 5010);
DISPLAY INVISIBLE (-1790 5010);
FORCEPROP 1 LASTPIN (-1800 5000) BN 61
J 2
(-1750 5010);
DISPLAY 0.617021 (-1750 5010);
PAINT PINK (-1750 5010);
FORCEPROP 2 LAST CDS_LIB mstr_standard
J 2
(-1750 5000);
DISPLAY 0.787234 (-1750 5000);
PAINT MONO (-1750 5000);
DISPLAY INVISIBLE (-1750 5000);
FORCEPROP 1 LAST BODY_TYPE PLUMBING
J 2
(-1750 4950);
DISPLAY 1.234043 (-1750 4950);
PAINT GREEN (-1750 4950);
DISPLAY INVISIBLE (-1750 4950);
FORCEPROP 1 LAST HDL_TAP TRUE
J 2
(-2075 4875);
DISPLAY 1.234043 (-2075 4875);
PAINT GREEN (-2075 4875);
DISPLAY INVISIBLE (-2075 4875);
FORCEPROP 1 LAST PATH I48
J 2
(-1750 5000);
DISPLAY 0.936170 (-1750 5000);
PAINT GREEN (-1750 5000);
DISPLAY INVISIBLE (-1750 5000);
FORCEADD TAP..6
R 2
(-1750 5050);
FORCEPROP 3 LASTPIN (-1800 5050) SIG_NAME M_D_DQ<60>
J 0
(-1790 5060);
DISPLAY 0.659574 (-1790 5060);
PAINT MONO (-1790 5060);
DISPLAY INVISIBLE (-1790 5060);
FORCEPROP 1 LASTPIN (-1800 5050) BN 60
J 2
(-1750 5060);
DISPLAY 0.617021 (-1750 5060);
PAINT PINK (-1750 5060);
FORCEPROP 2 LAST CDS_LIB mstr_standard
J 2
(-1750 5050);
DISPLAY 0.787234 (-1750 5050);
PAINT MONO (-1750 5050);
DISPLAY INVISIBLE (-1750 5050);
FORCEPROP 1 LAST BODY_TYPE PLUMBING
J 2
(-1750 5000);
DISPLAY 1.234043 (-1750 5000);
PAINT GREEN (-1750 5000);
DISPLAY INVISIBLE (-1750 5000);
FORCEPROP 1 LAST HDL_TAP TRUE
J 2
(-2075 4925);
DISPLAY 1.234043 (-2075 4925);
PAINT GREEN (-2075 4925);
DISPLAY INVISIBLE (-2075 4925);
FORCEPROP 1 LAST PATH I49
J 2
(-1750 5050);
DISPLAY 0.936170 (-1750 5050);
PAINT GREEN (-1750 5050);
DISPLAY INVISIBLE (-1750 5050);
FORCEADD TAP..6
R 2
(900 5050);
FORCEPROP 3 LASTPIN (850 5050) SIG_NAME M_D_DQS_DN<16>
J 0
(860 5060);
DISPLAY 0.659574 (860 5060);
PAINT MONO (860 5060);
DISPLAY INVISIBLE (860 5060);
FORCEPROP 1 LASTPIN (850 5050) BN 16
J 2
(900 5060);
DISPLAY 0.617021 (900 5060);
PAINT PINK (900 5060);
FORCEPROP 2 LAST CDS_LIB mstr_standard
J 0
(900 5050);
DISPLAY 0.787234 (900 5050);
PAINT MONO (900 5050);
DISPLAY INVISIBLE (900 5050);
FORCEPROP 1 LAST BODY_TYPE PLUMBING
J 2
(900 5000);
DISPLAY 1.234043 (900 5000);
PAINT GREEN (900 5000);
DISPLAY INVISIBLE (900 5000);
FORCEPROP 1 LAST HDL_TAP TRUE
J 2
(575 4925);
DISPLAY 1.234043 (575 4925);
PAINT GREEN (575 4925);
DISPLAY INVISIBLE (575 4925);
FORCEPROP 1 LAST PATH I5
J 2
(900 5050);
DISPLAY 0.936170 (900 5050);
PAINT GREEN (900 5050);
DISPLAY INVISIBLE (900 5050);
FORCEADD TAP..6
R 2
(-1750 4950);
FORCEPROP 3 LASTPIN (-1800 4950) SIG_NAME M_D_DQ<58>
J 0
(-1790 4960);
DISPLAY 0.659574 (-1790 4960);
PAINT MONO (-1790 4960);
DISPLAY INVISIBLE (-1790 4960);
FORCEPROP 1 LASTPIN (-1800 4950) BN 58
J 2
(-1750 4960);
DISPLAY 0.617021 (-1750 4960);
PAINT PINK (-1750 4960);
FORCEPROP 2 LAST CDS_LIB mstr_standard
J 2
(-1750 4950);
DISPLAY 0.787234 (-1750 4950);
PAINT MONO (-1750 4950);
DISPLAY INVISIBLE (-1750 4950);
FORCEPROP 1 LAST BODY_TYPE PLUMBING
J 2
(-1750 4900);
DISPLAY 1.234043 (-1750 4900);
PAINT GREEN (-1750 4900);
DISPLAY INVISIBLE (-1750 4900);
FORCEPROP 1 LAST HDL_TAP TRUE
J 2
(-2075 4825);
DISPLAY 1.234043 (-2075 4825);
PAINT GREEN (-2075 4825);
DISPLAY INVISIBLE (-2075 4825);
FORCEPROP 1 LAST PATH I50
J 2
(-1750 4950);
DISPLAY 0.936170 (-1750 4950);
PAINT GREEN (-1750 4950);
DISPLAY INVISIBLE (-1750 4950);
FORCEADD TAP..6
R 2
(-1750 4850);
FORCEPROP 3 LASTPIN (-1800 4850) SIG_NAME M_D_DQ<56>
J 0
(-1790 4860);
DISPLAY 0.659574 (-1790 4860);
PAINT MONO (-1790 4860);
DISPLAY INVISIBLE (-1790 4860);
FORCEPROP 1 LASTPIN (-1800 4850) BN 56
J 2
(-1750 4860);
DISPLAY 0.617021 (-1750 4860);
PAINT PINK (-1750 4860);
FORCEPROP 2 LAST CDS_LIB mstr_standard
J 2
(-1750 4850);
DISPLAY 0.787234 (-1750 4850);
PAINT MONO (-1750 4850);
DISPLAY INVISIBLE (-1750 4850);
FORCEPROP 1 LAST BODY_TYPE PLUMBING
J 2
(-1750 4800);
DISPLAY 1.234043 (-1750 4800);
PAINT GREEN (-1750 4800);
DISPLAY INVISIBLE (-1750 4800);
FORCEPROP 1 LAST HDL_TAP TRUE
J 2
(-2075 4725);
DISPLAY 1.234043 (-2075 4725);
PAINT GREEN (-2075 4725);
DISPLAY INVISIBLE (-2075 4725);
FORCEPROP 1 LAST PATH I51
J 2
(-1750 4850);
DISPLAY 0.936170 (-1750 4850);
PAINT GREEN (-1750 4850);
DISPLAY INVISIBLE (-1750 4850);
FORCEADD TAP..6
R 2
(-1750 4900);
FORCEPROP 3 LASTPIN (-1800 4900) SIG_NAME M_D_DQ<59>
J 0
(-1790 4910);
DISPLAY 0.659574 (-1790 4910);
PAINT MONO (-1790 4910);
DISPLAY INVISIBLE (-1790 4910);
FORCEPROP 1 LASTPIN (-1800 4900) BN 59
J 2
(-1750 4910);
DISPLAY 0.617021 (-1750 4910);
PAINT PINK (-1750 4910);
FORCEPROP 2 LAST CDS_LIB mstr_standard
J 2
(-1750 4900);
DISPLAY 0.787234 (-1750 4900);
PAINT MONO (-1750 4900);
DISPLAY INVISIBLE (-1750 4900);
FORCEPROP 1 LAST BODY_TYPE PLUMBING
J 2
(-1750 4850);
DISPLAY 1.234043 (-1750 4850);
PAINT GREEN (-1750 4850);
DISPLAY INVISIBLE (-1750 4850);
FORCEPROP 1 LAST HDL_TAP TRUE
J 2
(-2075 4775);
DISPLAY 1.234043 (-2075 4775);
PAINT GREEN (-2075 4775);
DISPLAY INVISIBLE (-2075 4775);
FORCEPROP 1 LAST PATH I52
J 2
(-1750 4900);
DISPLAY 0.936170 (-1750 4900);
PAINT GREEN (-1750 4900);
DISPLAY INVISIBLE (-1750 4900);
FORCEADD TAP..6
R 2
(-1750 4800);
FORCEPROP 3 LASTPIN (-1800 4800) SIG_NAME M_D_DQ<57>
J 0
(-1790 4810);
DISPLAY 0.659574 (-1790 4810);
PAINT MONO (-1790 4810);
DISPLAY INVISIBLE (-1790 4810);
FORCEPROP 1 LASTPIN (-1800 4800) BN 57
J 2
(-1750 4810);
DISPLAY 0.617021 (-1750 4810);
PAINT PINK (-1750 4810);
FORCEPROP 2 LAST CDS_LIB mstr_standard
J 2
(-1750 4800);
DISPLAY 0.787234 (-1750 4800);
PAINT MONO (-1750 4800);
DISPLAY INVISIBLE (-1750 4800);
FORCEPROP 1 LAST BODY_TYPE PLUMBING
J 2
(-1750 4750);
DISPLAY 1.234043 (-1750 4750);
PAINT GREEN (-1750 4750);
DISPLAY INVISIBLE (-1750 4750);
FORCEPROP 1 LAST HDL_TAP TRUE
J 2
(-2075 4675);
DISPLAY 1.234043 (-2075 4675);
PAINT GREEN (-2075 4675);
DISPLAY INVISIBLE (-2075 4675);
FORCEPROP 1 LAST PATH I53
J 2
(-1750 4800);
DISPLAY 0.936170 (-1750 4800);
PAINT GREEN (-1750 4800);
DISPLAY INVISIBLE (-1750 4800);
FORCEADD TAP..6
R 2
(-1750 4750);
FORCEPROP 3 LASTPIN (-1800 4750) SIG_NAME M_D_DQ<54>
J 0
(-1790 4760);
DISPLAY 0.659574 (-1790 4760);
PAINT MONO (-1790 4760);
DISPLAY INVISIBLE (-1790 4760);
FORCEPROP 1 LASTPIN (-1800 4750) BN 54
J 2
(-1750 4760);
DISPLAY 0.617021 (-1750 4760);
PAINT PINK (-1750 4760);
FORCEPROP 2 LAST CDS_LIB mstr_standard
J 2
(-1750 4750);
DISPLAY 0.787234 (-1750 4750);
PAINT MONO (-1750 4750);
DISPLAY INVISIBLE (-1750 4750);
FORCEPROP 1 LAST BODY_TYPE PLUMBING
J 2
(-1750 4700);
DISPLAY 1.234043 (-1750 4700);
PAINT GREEN (-1750 4700);
DISPLAY INVISIBLE (-1750 4700);
FORCEPROP 1 LAST HDL_TAP TRUE
J 2
(-2075 4625);
DISPLAY 1.234043 (-2075 4625);
PAINT GREEN (-2075 4625);
DISPLAY INVISIBLE (-2075 4625);
FORCEPROP 1 LAST PATH I54
J 2
(-1750 4750);
DISPLAY 0.936170 (-1750 4750);
PAINT GREEN (-1750 4750);
DISPLAY INVISIBLE (-1750 4750);
FORCEADD TAP..6
R 2
(-1750 4650);
FORCEPROP 3 LASTPIN (-1800 4650) SIG_NAME M_D_DQ<52>
J 0
(-1790 4660);
DISPLAY 0.659574 (-1790 4660);
PAINT MONO (-1790 4660);
DISPLAY INVISIBLE (-1790 4660);
FORCEPROP 1 LASTPIN (-1800 4650) BN 52
J 2
(-1750 4660);
DISPLAY 0.617021 (-1750 4660);
PAINT PINK (-1750 4660);
FORCEPROP 2 LAST CDS_LIB mstr_standard
J 2
(-1750 4650);
DISPLAY 0.787234 (-1750 4650);
PAINT MONO (-1750 4650);
DISPLAY INVISIBLE (-1750 4650);
FORCEPROP 1 LAST BODY_TYPE PLUMBING
J 2
(-1750 4600);
DISPLAY 1.234043 (-1750 4600);
PAINT GREEN (-1750 4600);
DISPLAY INVISIBLE (-1750 4600);
FORCEPROP 1 LAST HDL_TAP TRUE
J 2
(-2075 4525);
DISPLAY 1.234043 (-2075 4525);
PAINT GREEN (-2075 4525);
DISPLAY INVISIBLE (-2075 4525);
FORCEPROP 1 LAST PATH I55
J 2
(-1750 4650);
DISPLAY 0.936170 (-1750 4650);
PAINT GREEN (-1750 4650);
DISPLAY INVISIBLE (-1750 4650);
FORCEADD TAP..6
R 2
(-1750 4700);
FORCEPROP 3 LASTPIN (-1800 4700) SIG_NAME M_D_DQ<55>
J 0
(-1790 4710);
DISPLAY 0.659574 (-1790 4710);
PAINT MONO (-1790 4710);
DISPLAY INVISIBLE (-1790 4710);
FORCEPROP 1 LASTPIN (-1800 4700) BN 55
J 2
(-1750 4710);
DISPLAY 0.617021 (-1750 4710);
PAINT PINK (-1750 4710);
FORCEPROP 2 LAST CDS_LIB mstr_standard
J 2
(-1750 4700);
DISPLAY 0.787234 (-1750 4700);
PAINT MONO (-1750 4700);
DISPLAY INVISIBLE (-1750 4700);
FORCEPROP 1 LAST BODY_TYPE PLUMBING
J 2
(-1750 4650);
DISPLAY 1.234043 (-1750 4650);
PAINT GREEN (-1750 4650);
DISPLAY INVISIBLE (-1750 4650);
FORCEPROP 1 LAST HDL_TAP TRUE
J 2
(-2075 4575);
DISPLAY 1.234043 (-2075 4575);
PAINT GREEN (-2075 4575);
DISPLAY INVISIBLE (-2075 4575);
FORCEPROP 1 LAST PATH I56
J 2
(-1750 4700);
DISPLAY 0.936170 (-1750 4700);
PAINT GREEN (-1750 4700);
DISPLAY INVISIBLE (-1750 4700);
FORCEADD TAP..6
R 2
(-1750 4600);
FORCEPROP 3 LASTPIN (-1800 4600) SIG_NAME M_D_DQ<53>
J 0
(-1790 4610);
DISPLAY 0.659574 (-1790 4610);
PAINT MONO (-1790 4610);
DISPLAY INVISIBLE (-1790 4610);
FORCEPROP 1 LASTPIN (-1800 4600) BN 53
J 2
(-1750 4610);
DISPLAY 0.617021 (-1750 4610);
PAINT PINK (-1750 4610);
FORCEPROP 2 LAST CDS_LIB mstr_standard
J 2
(-1750 4600);
DISPLAY 0.787234 (-1750 4600);
PAINT MONO (-1750 4600);
DISPLAY INVISIBLE (-1750 4600);
FORCEPROP 1 LAST BODY_TYPE PLUMBING
J 2
(-1750 4550);
DISPLAY 1.234043 (-1750 4550);
PAINT GREEN (-1750 4550);
DISPLAY INVISIBLE (-1750 4550);
FORCEPROP 1 LAST HDL_TAP TRUE
J 2
(-2075 4475);
DISPLAY 1.234043 (-2075 4475);
PAINT GREEN (-2075 4475);
DISPLAY INVISIBLE (-2075 4475);
FORCEPROP 1 LAST PATH I57
J 2
(-1750 4600);
DISPLAY 0.936170 (-1750 4600);
PAINT GREEN (-1750 4600);
DISPLAY INVISIBLE (-1750 4600);
FORCEADD TAP..6
R 2
(-1750 4550);
FORCEPROP 3 LASTPIN (-1800 4550) SIG_NAME M_D_DQ<50>
J 0
(-1790 4560);
DISPLAY 0.659574 (-1790 4560);
PAINT MONO (-1790 4560);
DISPLAY INVISIBLE (-1790 4560);
FORCEPROP 1 LASTPIN (-1800 4550) BN 50
J 2
(-1750 4560);
DISPLAY 0.617021 (-1750 4560);
PAINT PINK (-1750 4560);
FORCEPROP 2 LAST CDS_LIB mstr_standard
J 2
(-1750 4550);
DISPLAY 0.787234 (-1750 4550);
PAINT MONO (-1750 4550);
DISPLAY INVISIBLE (-1750 4550);
FORCEPROP 1 LAST BODY_TYPE PLUMBING
J 2
(-1750 4500);
DISPLAY 1.234043 (-1750 4500);
PAINT GREEN (-1750 4500);
DISPLAY INVISIBLE (-1750 4500);
FORCEPROP 1 LAST HDL_TAP TRUE
J 2
(-2075 4425);
DISPLAY 1.234043 (-2075 4425);
PAINT GREEN (-2075 4425);
DISPLAY INVISIBLE (-2075 4425);
FORCEPROP 1 LAST PATH I58
J 2
(-1750 4550);
DISPLAY 0.936170 (-1750 4550);
PAINT GREEN (-1750 4550);
DISPLAY INVISIBLE (-1750 4550);
FORCEADD TAP..6
R 2
(-1750 4500);
FORCEPROP 3 LASTPIN (-1800 4500) SIG_NAME M_D_DQ<51>
J 0
(-1790 4510);
DISPLAY 0.659574 (-1790 4510);
PAINT MONO (-1790 4510);
DISPLAY INVISIBLE (-1790 4510);
FORCEPROP 1 LASTPIN (-1800 4500) BN 51
J 2
(-1750 4510);
DISPLAY 0.617021 (-1750 4510);
PAINT PINK (-1750 4510);
FORCEPROP 2 LAST CDS_LIB mstr_standard
J 2
(-1750 4500);
DISPLAY 0.787234 (-1750 4500);
PAINT MONO (-1750 4500);
DISPLAY INVISIBLE (-1750 4500);
FORCEPROP 1 LAST BODY_TYPE PLUMBING
J 2
(-1750 4450);
DISPLAY 1.234043 (-1750 4450);
PAINT GREEN (-1750 4450);
DISPLAY INVISIBLE (-1750 4450);
FORCEPROP 1 LAST HDL_TAP TRUE
J 2
(-2075 4375);
DISPLAY 1.234043 (-2075 4375);
PAINT GREEN (-2075 4375);
DISPLAY INVISIBLE (-2075 4375);
FORCEPROP 1 LAST PATH I59
J 2
(-1750 4500);
DISPLAY 0.936170 (-1750 4500);
PAINT GREEN (-1750 4500);
DISPLAY INVISIBLE (-1750 4500);
FORCEADD TAP..6
R 2
(900 4950);
FORCEPROP 3 LASTPIN (850 4950) SIG_NAME M_D_DQS_DN<15>
J 0
(860 4960);
DISPLAY 0.659574 (860 4960);
PAINT MONO (860 4960);
DISPLAY INVISIBLE (860 4960);
FORCEPROP 1 LASTPIN (850 4950) BN 15
J 2
(900 4960);
DISPLAY 0.617021 (900 4960);
PAINT PINK (900 4960);
FORCEPROP 2 LAST CDS_LIB mstr_standard
J 0
(900 4950);
DISPLAY 0.787234 (900 4950);
PAINT MONO (900 4950);
DISPLAY INVISIBLE (900 4950);
FORCEPROP 1 LAST BODY_TYPE PLUMBING
J 2
(900 4900);
DISPLAY 1.234043 (900 4900);
PAINT GREEN (900 4900);
DISPLAY INVISIBLE (900 4900);
FORCEPROP 1 LAST HDL_TAP TRUE
J 2
(575 4825);
DISPLAY 1.234043 (575 4825);
PAINT GREEN (575 4825);
DISPLAY INVISIBLE (575 4825);
FORCEPROP 1 LAST PATH I6
J 2
(900 4950);
DISPLAY 0.936170 (900 4950);
PAINT GREEN (900 4950);
DISPLAY INVISIBLE (900 4950);
FORCEADD TAP..6
R 2
(-1750 4450);
FORCEPROP 3 LASTPIN (-1800 4450) SIG_NAME M_D_DQ<48>
J 0
(-1790 4460);
DISPLAY 0.659574 (-1790 4460);
PAINT MONO (-1790 4460);
DISPLAY INVISIBLE (-1790 4460);
FORCEPROP 1 LASTPIN (-1800 4450) BN 48
J 2
(-1750 4460);
DISPLAY 0.617021 (-1750 4460);
PAINT PINK (-1750 4460);
FORCEPROP 2 LAST CDS_LIB mstr_standard
J 2
(-1750 4450);
DISPLAY 0.787234 (-1750 4450);
PAINT MONO (-1750 4450);
DISPLAY INVISIBLE (-1750 4450);
FORCEPROP 1 LAST BODY_TYPE PLUMBING
J 2
(-1750 4400);
DISPLAY 1.234043 (-1750 4400);
PAINT GREEN (-1750 4400);
DISPLAY INVISIBLE (-1750 4400);
FORCEPROP 1 LAST HDL_TAP TRUE
J 2
(-2075 4325);
DISPLAY 1.234043 (-2075 4325);
PAINT GREEN (-2075 4325);
DISPLAY INVISIBLE (-2075 4325);
FORCEPROP 1 LAST PATH I60
J 2
(-1750 4450);
DISPLAY 0.936170 (-1750 4450);
PAINT GREEN (-1750 4450);
DISPLAY INVISIBLE (-1750 4450);
FORCEADD TAP..6
R 2
(-1750 4350);
FORCEPROP 3 LASTPIN (-1800 4350) SIG_NAME M_D_DQ<46>
J 0
(-1790 4360);
DISPLAY 0.659574 (-1790 4360);
PAINT MONO (-1790 4360);
DISPLAY INVISIBLE (-1790 4360);
FORCEPROP 1 LASTPIN (-1800 4350) BN 46
J 2
(-1750 4360);
DISPLAY 0.617021 (-1750 4360);
PAINT PINK (-1750 4360);
FORCEPROP 2 LAST CDS_LIB mstr_standard
J 2
(-1750 4350);
DISPLAY 0.787234 (-1750 4350);
PAINT MONO (-1750 4350);
DISPLAY INVISIBLE (-1750 4350);
FORCEPROP 1 LAST BODY_TYPE PLUMBING
J 2
(-1750 4300);
DISPLAY 1.234043 (-1750 4300);
PAINT GREEN (-1750 4300);
DISPLAY INVISIBLE (-1750 4300);
FORCEPROP 1 LAST HDL_TAP TRUE
J 2
(-2075 4225);
DISPLAY 1.234043 (-2075 4225);
PAINT GREEN (-2075 4225);
DISPLAY INVISIBLE (-2075 4225);
FORCEPROP 1 LAST PATH I61
J 2
(-1750 4350);
DISPLAY 0.936170 (-1750 4350);
PAINT GREEN (-1750 4350);
DISPLAY INVISIBLE (-1750 4350);
FORCEADD TAP..6
R 2
(-1750 4400);
FORCEPROP 3 LASTPIN (-1800 4400) SIG_NAME M_D_DQ<49>
J 0
(-1790 4410);
DISPLAY 0.659574 (-1790 4410);
PAINT MONO (-1790 4410);
DISPLAY INVISIBLE (-1790 4410);
FORCEPROP 1 LASTPIN (-1800 4400) BN 49
J 2
(-1750 4410);
DISPLAY 0.617021 (-1750 4410);
PAINT PINK (-1750 4410);
FORCEPROP 2 LAST CDS_LIB mstr_standard
J 2
(-1750 4400);
DISPLAY 0.787234 (-1750 4400);
PAINT MONO (-1750 4400);
DISPLAY INVISIBLE (-1750 4400);
FORCEPROP 1 LAST BODY_TYPE PLUMBING
J 2
(-1750 4350);
DISPLAY 1.234043 (-1750 4350);
PAINT GREEN (-1750 4350);
DISPLAY INVISIBLE (-1750 4350);
FORCEPROP 1 LAST HDL_TAP TRUE
J 2
(-2075 4275);
DISPLAY 1.234043 (-2075 4275);
PAINT GREEN (-2075 4275);
DISPLAY INVISIBLE (-2075 4275);
FORCEPROP 1 LAST PATH I62
J 2
(-1750 4400);
DISPLAY 0.936170 (-1750 4400);
PAINT GREEN (-1750 4400);
DISPLAY INVISIBLE (-1750 4400);
FORCEADD TAP..6
R 2
(-1750 4300);
FORCEPROP 3 LASTPIN (-1800 4300) SIG_NAME M_D_DQ<47>
J 0
(-1790 4310);
DISPLAY 0.659574 (-1790 4310);
PAINT MONO (-1790 4310);
DISPLAY INVISIBLE (-1790 4310);
FORCEPROP 1 LASTPIN (-1800 4300) BN 47
J 2
(-1750 4310);
DISPLAY 0.617021 (-1750 4310);
PAINT PINK (-1750 4310);
FORCEPROP 2 LAST CDS_LIB mstr_standard
J 2
(-1750 4300);
DISPLAY 0.787234 (-1750 4300);
PAINT MONO (-1750 4300);
DISPLAY INVISIBLE (-1750 4300);
FORCEPROP 1 LAST BODY_TYPE PLUMBING
J 2
(-1750 4250);
DISPLAY 1.234043 (-1750 4250);
PAINT GREEN (-1750 4250);
DISPLAY INVISIBLE (-1750 4250);
FORCEPROP 1 LAST HDL_TAP TRUE
J 2
(-2075 4175);
DISPLAY 1.234043 (-2075 4175);
PAINT GREEN (-2075 4175);
DISPLAY INVISIBLE (-2075 4175);
FORCEPROP 1 LAST PATH I63
J 2
(-1750 4300);
DISPLAY 0.936170 (-1750 4300);
PAINT GREEN (-1750 4300);
DISPLAY INVISIBLE (-1750 4300);
FORCEADD TAP..6
R 2
(-1750 4250);
FORCEPROP 3 LASTPIN (-1800 4250) SIG_NAME M_D_DQ<44>
J 0
(-1790 4260);
DISPLAY 0.659574 (-1790 4260);
PAINT MONO (-1790 4260);
DISPLAY INVISIBLE (-1790 4260);
FORCEPROP 1 LASTPIN (-1800 4250) BN 44
J 2
(-1750 4260);
DISPLAY 0.617021 (-1750 4260);
PAINT PINK (-1750 4260);
FORCEPROP 2 LAST CDS_LIB mstr_standard
J 2
(-1750 4250);
DISPLAY 0.787234 (-1750 4250);
PAINT MONO (-1750 4250);
DISPLAY INVISIBLE (-1750 4250);
FORCEPROP 1 LAST BODY_TYPE PLUMBING
J 2
(-1750 4200);
DISPLAY 1.234043 (-1750 4200);
PAINT GREEN (-1750 4200);
DISPLAY INVISIBLE (-1750 4200);
FORCEPROP 1 LAST HDL_TAP TRUE
J 2
(-2075 4125);
DISPLAY 1.234043 (-2075 4125);
PAINT GREEN (-2075 4125);
DISPLAY INVISIBLE (-2075 4125);
FORCEPROP 1 LAST PATH I64
J 2
(-1750 4250);
DISPLAY 0.936170 (-1750 4250);
PAINT GREEN (-1750 4250);
DISPLAY INVISIBLE (-1750 4250);
FORCEADD TAP..6
R 2
(-1750 4200);
FORCEPROP 3 LASTPIN (-1800 4200) SIG_NAME M_D_DQ<45>
J 0
(-1790 4210);
DISPLAY 0.659574 (-1790 4210);
PAINT MONO (-1790 4210);
DISPLAY INVISIBLE (-1790 4210);
FORCEPROP 1 LASTPIN (-1800 4200) BN 45
J 2
(-1750 4210);
DISPLAY 0.617021 (-1750 4210);
PAINT PINK (-1750 4210);
FORCEPROP 2 LAST CDS_LIB mstr_standard
J 2
(-1750 4200);
DISPLAY 0.787234 (-1750 4200);
PAINT MONO (-1750 4200);
DISPLAY INVISIBLE (-1750 4200);
FORCEPROP 1 LAST BODY_TYPE PLUMBING
J 2
(-1750 4150);
DISPLAY 1.234043 (-1750 4150);
PAINT GREEN (-1750 4150);
DISPLAY INVISIBLE (-1750 4150);
FORCEPROP 1 LAST HDL_TAP TRUE
J 2
(-2075 4075);
DISPLAY 1.234043 (-2075 4075);
PAINT GREEN (-2075 4075);
DISPLAY INVISIBLE (-2075 4075);
FORCEPROP 1 LAST PATH I65
J 2
(-1750 4200);
DISPLAY 0.936170 (-1750 4200);
PAINT GREEN (-1750 4200);
DISPLAY INVISIBLE (-1750 4200);
FORCEADD SCONN288_H44441004..2
(-50 4350);
FORCEPROP 1 LAST LOCATION J4B1
J 0
(-450 5450);
DISPLAY 0.617021 (-450 5450);
PAINT AQUA (-450 5450);
FORCEPROP 1 LAST PART_NUMBER H44441-004
J 0
(-450 3250);
DISPLAY 0.617021 (-450 3250);
PAINT BLUE (-450 3250);
FORCEPROP 1 LAST MATERIAL SCONN
J 0
(-450 5400);
DISPLAY 0.617021 (-450 5400);
PAINT SKYBLUE (-450 5400);
FORCEPROP 2 LASTPIN (400 5200) $PN 51
J 0
(410 5210);
DISPLAY 0.617021 (410 5210);
PAINT ORANGE (410 5210);
FORCEPROP 2 LASTPIN (400 5150) $PN 52
J 0
(410 5160);
DISPLAY 0.617021 (410 5160);
PAINT ORANGE (410 5160);
FORCEPROP 2 LASTPIN (400 5100) $PN 132
J 0
(410 5110);
DISPLAY 0.617021 (410 5110);
PAINT ORANGE (410 5110);
FORCEPROP 2 LASTPIN (400 5050) $PN 133
J 0
(410 5060);
DISPLAY 0.617021 (410 5060);
PAINT ORANGE (410 5060);
FORCEPROP 2 LASTPIN (400 5000) $PN 121
J 0
(410 5010);
DISPLAY 0.617021 (410 5010);
PAINT ORANGE (410 5010);
FORCEPROP 2 LASTPIN (400 4950) $PN 122
J 0
(410 4960);
DISPLAY 0.617021 (410 4960);
PAINT ORANGE (410 4960);
FORCEPROP 2 LASTPIN (400 4900) $PN 110
J 0
(410 4910);
DISPLAY 0.617021 (410 4910);
PAINT ORANGE (410 4910);
FORCEPROP 2 LASTPIN (400 4850) $PN 111
J 0
(410 4860);
DISPLAY 0.617021 (410 4860);
PAINT ORANGE (410 4860);
FORCEPROP 2 LASTPIN (400 4800) $PN 99
J 0
(410 4810);
DISPLAY 0.617021 (410 4810);
PAINT ORANGE (410 4810);
FORCEPROP 2 LASTPIN (400 4750) $PN 100
J 0
(410 4760);
DISPLAY 0.617021 (410 4760);
PAINT ORANGE (410 4760);
FORCEPROP 2 LASTPIN (400 4700) $PN 40
J 0
(410 4710);
DISPLAY 0.617021 (410 4710);
PAINT ORANGE (410 4710);
FORCEPROP 2 LASTPIN (400 4650) $PN 41
J 0
(410 4660);
DISPLAY 0.617021 (410 4660);
PAINT ORANGE (410 4660);
FORCEPROP 2 LASTPIN (400 4600) $PN 29
J 0
(410 4610);
DISPLAY 0.617021 (410 4610);
PAINT ORANGE (410 4610);
FORCEPROP 2 LASTPIN (400 4550) $PN 30
J 0
(410 4560);
DISPLAY 0.617021 (410 4560);
PAINT ORANGE (410 4560);
FORCEPROP 2 LASTPIN (400 4500) $PN 18
J 0
(410 4510);
DISPLAY 0.617021 (410 4510);
PAINT ORANGE (410 4510);
FORCEPROP 2 LASTPIN (400 4450) $PN 19
J 0
(410 4460);
DISPLAY 0.617021 (410 4460);
PAINT ORANGE (410 4460);
FORCEPROP 2 LASTPIN (400 4400) $PN 7
J 0
(410 4410);
DISPLAY 0.617021 (410 4410);
PAINT ORANGE (410 4410);
FORCEPROP 2 LASTPIN (400 4350) $PN 8
J 0
(410 4360);
DISPLAY 0.617021 (410 4360);
PAINT ORANGE (410 4360);
FORCEPROP 2 LASTPIN (400 4300) $PN 197
J 0
(410 4310);
DISPLAY 0.617021 (410 4310);
PAINT ORANGE (410 4310);
FORCEPROP 2 LASTPIN (400 4250) $PN 196
J 0
(410 4260);
DISPLAY 0.617021 (410 4260);
PAINT ORANGE (410 4260);
FORCEPROP 2 LASTPIN (400 4200) $PN 278
J 0
(410 4210);
DISPLAY 0.617021 (410 4210);
PAINT ORANGE (410 4210);
FORCEPROP 2 LASTPIN (400 4150) $PN 277
J 0
(410 4160);
DISPLAY 0.617021 (410 4160);
PAINT ORANGE (410 4160);
FORCEPROP 2 LASTPIN (400 4100) $PN 267
J 0
(410 4110);
DISPLAY 0.617021 (410 4110);
PAINT ORANGE (410 4110);
FORCEPROP 2 LASTPIN (400 4050) $PN 266
J 0
(410 4060);
DISPLAY 0.617021 (410 4060);
PAINT ORANGE (410 4060);
FORCEPROP 2 LASTPIN (400 4000) $PN 256
J 0
(410 4010);
DISPLAY 0.617021 (410 4010);
PAINT ORANGE (410 4010);
FORCEPROP 2 LASTPIN (400 3950) $PN 255
J 0
(410 3960);
DISPLAY 0.617021 (410 3960);
PAINT ORANGE (410 3960);
FORCEPROP 2 LASTPIN (400 3900) $PN 245
J 0
(410 3910);
DISPLAY 0.617021 (410 3910);
PAINT ORANGE (410 3910);
FORCEPROP 2 LASTPIN (400 3850) $PN 244
J 0
(410 3860);
DISPLAY 0.617021 (410 3860);
PAINT ORANGE (410 3860);
FORCEPROP 2 LASTPIN (400 3800) $PN 186
J 0
(410 3810);
DISPLAY 0.617021 (410 3810);
PAINT ORANGE (410 3810);
FORCEPROP 2 LASTPIN (400 3750) $PN 185
J 0
(410 3760);
DISPLAY 0.617021 (410 3760);
PAINT ORANGE (410 3760);
FORCEPROP 2 LASTPIN (400 3700) $PN 175
J 0
(410 3710);
DISPLAY 0.617021 (410 3710);
PAINT ORANGE (410 3710);
FORCEPROP 2 LASTPIN (400 3650) $PN 174
J 0
(410 3660);
DISPLAY 0.617021 (410 3660);
PAINT ORANGE (410 3660);
FORCEPROP 2 LASTPIN (400 3600) $PN 164
J 0
(410 3610);
DISPLAY 0.617021 (410 3610);
PAINT ORANGE (410 3610);
FORCEPROP 2 LASTPIN (400 3550) $PN 163
J 0
(410 3560);
DISPLAY 0.617021 (410 3560);
PAINT ORANGE (410 3560);
FORCEPROP 2 LASTPIN (400 3500) $PN 153
J 0
(410 3510);
DISPLAY 0.617021 (410 3510);
PAINT ORANGE (410 3510);
FORCEPROP 2 LASTPIN (400 3450) $PN 152
J 0
(410 3460);
DISPLAY 0.617021 (410 3460);
PAINT ORANGE (410 3460);
FORCEPROP 1 LAST PACK_TYPE PIP
J 0
(-450 5500);
PAINT SKYBLUE (-450 5500);
DISPLAY INVISIBLE (-450 5500);
FORCEPROP 2 LAST BOM_COST MEM
J 0
(-50 4350);
PAINT ORANGE (-50 4350);
DISPLAY INVISIBLE (-50 4350);
FORCEPROP 2 LAST CDS_LIB mstr_sconn
J 0
(-50 4350);
PAINT ORANGE (-50 4350);
DISPLAY INVISIBLE (-50 4350);
FORCEPROP 2 LAST SEC_TYPE PIP
J 0
(-450 5500);
DISPLAY 1.021277 (-450 5500);
PAINT ORANGE (-450 5500);
DISPLAY INVISIBLE (-450 5500);
FORCEPROP 2 LAST SEC 2
J 0
(-450 5500);
DISPLAY 0.680851 (-450 5500);
PAINT MONO (-450 5500);
DISPLAY INVISIBLE (-450 5500);
FORCEPROP 2 LAST CDS_LOCATION J4B1
J 0
(-450 5450);
DISPLAY 0.617021 (-450 5450);
PAINT AQUA (-450 5450);
DISPLAY INVISIBLE (-450 5450);
FORCEPROP 1 LAST PATH I66
J 0
(-50 5400);
PAINT GREEN (-50 5400);
DISPLAY INVISIBLE (-50 5400);
FORCEPROP 2 LAST ROOM DDR4_CH_D
J 0
(-50 4350);
PAINT ORANGE (-50 4350);
DISPLAY INVISIBLE (-50 4350);
FORCEADD TAP..6
R 2
(-1750 4150);
FORCEPROP 3 LASTPIN (-1800 4150) SIG_NAME M_D_DQ<42>
J 0
(-1790 4160);
DISPLAY 0.659574 (-1790 4160);
PAINT MONO (-1790 4160);
DISPLAY INVISIBLE (-1790 4160);
FORCEPROP 1 LASTPIN (-1800 4150) BN 42
J 2
(-1750 4160);
DISPLAY 0.617021 (-1750 4160);
PAINT PINK (-1750 4160);
FORCEPROP 2 LAST CDS_LIB mstr_standard
J 2
(-1750 4150);
DISPLAY 0.787234 (-1750 4150);
PAINT MONO (-1750 4150);
DISPLAY INVISIBLE (-1750 4150);
FORCEPROP 1 LAST BODY_TYPE PLUMBING
J 2
(-1750 4100);
DISPLAY 1.234043 (-1750 4100);
PAINT GREEN (-1750 4100);
DISPLAY INVISIBLE (-1750 4100);
FORCEPROP 1 LAST HDL_TAP TRUE
J 2
(-2075 4025);
DISPLAY 1.234043 (-2075 4025);
PAINT GREEN (-2075 4025);
DISPLAY INVISIBLE (-2075 4025);
FORCEPROP 1 LAST PATH I67
J 2
(-1750 4150);
DISPLAY 0.936170 (-1750 4150);
PAINT GREEN (-1750 4150);
DISPLAY INVISIBLE (-1750 4150);
FORCEADD TAP..6
R 2
(-1750 4100);
FORCEPROP 3 LASTPIN (-1800 4100) SIG_NAME M_D_DQ<43>
J 0
(-1790 4110);
DISPLAY 0.659574 (-1790 4110);
PAINT MONO (-1790 4110);
DISPLAY INVISIBLE (-1790 4110);
FORCEPROP 1 LASTPIN (-1800 4100) BN 43
J 2
(-1750 4110);
DISPLAY 0.617021 (-1750 4110);
PAINT PINK (-1750 4110);
FORCEPROP 2 LAST CDS_LIB mstr_standard
J 2
(-1750 4100);
DISPLAY 0.787234 (-1750 4100);
PAINT MONO (-1750 4100);
DISPLAY INVISIBLE (-1750 4100);
FORCEPROP 1 LAST BODY_TYPE PLUMBING
J 2
(-1750 4050);
DISPLAY 1.234043 (-1750 4050);
PAINT GREEN (-1750 4050);
DISPLAY INVISIBLE (-1750 4050);
FORCEPROP 1 LAST HDL_TAP TRUE
J 2
(-2075 3975);
DISPLAY 1.234043 (-2075 3975);
PAINT GREEN (-2075 3975);
DISPLAY INVISIBLE (-2075 3975);
FORCEPROP 1 LAST PATH I68
J 2
(-1750 4100);
DISPLAY 0.936170 (-1750 4100);
PAINT GREEN (-1750 4100);
DISPLAY INVISIBLE (-1750 4100);
FORCEADD TAP..6
R 2
(-1750 4000);
FORCEPROP 3 LASTPIN (-1800 4000) SIG_NAME M_D_DQ<41>
J 0
(-1790 4010);
DISPLAY 0.659574 (-1790 4010);
PAINT MONO (-1790 4010);
DISPLAY INVISIBLE (-1790 4010);
FORCEPROP 1 LASTPIN (-1800 4000) BN 41
J 2
(-1750 4010);
DISPLAY 0.617021 (-1750 4010);
PAINT PINK (-1750 4010);
FORCEPROP 2 LAST CDS_LIB mstr_standard
J 2
(-1750 4000);
DISPLAY 0.787234 (-1750 4000);
PAINT MONO (-1750 4000);
DISPLAY INVISIBLE (-1750 4000);
FORCEPROP 1 LAST BODY_TYPE PLUMBING
J 2
(-1750 3950);
DISPLAY 1.234043 (-1750 3950);
PAINT GREEN (-1750 3950);
DISPLAY INVISIBLE (-1750 3950);
FORCEPROP 1 LAST HDL_TAP TRUE
J 2
(-2075 3875);
DISPLAY 1.234043 (-2075 3875);
PAINT GREEN (-2075 3875);
DISPLAY INVISIBLE (-2075 3875);
FORCEPROP 1 LAST PATH I69
J 2
(-1750 4000);
DISPLAY 0.936170 (-1750 4000);
PAINT GREEN (-1750 4000);
DISPLAY INVISIBLE (-1750 4000);
FORCEADD TAP..6
R 2
(900 4750);
FORCEPROP 3 LASTPIN (850 4750) SIG_NAME M_D_DQS_DN<13>
J 0
(860 4760);
DISPLAY 0.659574 (860 4760);
PAINT MONO (860 4760);
DISPLAY INVISIBLE (860 4760);
FORCEPROP 1 LASTPIN (850 4750) BN 13
J 2
(900 4760);
DISPLAY 0.617021 (900 4760);
PAINT PINK (900 4760);
FORCEPROP 2 LAST CDS_LIB mstr_standard
J 0
(900 4750);
DISPLAY 0.787234 (900 4750);
PAINT MONO (900 4750);
DISPLAY INVISIBLE (900 4750);
FORCEPROP 1 LAST BODY_TYPE PLUMBING
J 2
(900 4700);
DISPLAY 1.234043 (900 4700);
PAINT GREEN (900 4700);
DISPLAY INVISIBLE (900 4700);
FORCEPROP 1 LAST HDL_TAP TRUE
J 2
(575 4625);
DISPLAY 1.234043 (575 4625);
PAINT GREEN (575 4625);
DISPLAY INVISIBLE (575 4625);
FORCEPROP 1 LAST PATH I7
J 2
(900 4750);
DISPLAY 0.936170 (900 4750);
PAINT GREEN (900 4750);
DISPLAY INVISIBLE (900 4750);
FORCEADD TAP..6
R 2
(-1750 3950);
FORCEPROP 3 LASTPIN (-1800 3950) SIG_NAME M_D_DQ<38>
J 0
(-1790 3960);
DISPLAY 0.659574 (-1790 3960);
PAINT MONO (-1790 3960);
DISPLAY INVISIBLE (-1790 3960);
FORCEPROP 1 LASTPIN (-1800 3950) BN 38
J 2
(-1750 3960);
DISPLAY 0.617021 (-1750 3960);
PAINT PINK (-1750 3960);
FORCEPROP 2 LAST CDS_LIB mstr_standard
J 2
(-1750 3950);
DISPLAY 0.787234 (-1750 3950);
PAINT MONO (-1750 3950);
DISPLAY INVISIBLE (-1750 3950);
FORCEPROP 1 LAST BODY_TYPE PLUMBING
J 2
(-1750 3900);
DISPLAY 1.234043 (-1750 3900);
PAINT GREEN (-1750 3900);
DISPLAY INVISIBLE (-1750 3900);
FORCEPROP 1 LAST HDL_TAP TRUE
J 2
(-2075 3825);
DISPLAY 1.234043 (-2075 3825);
PAINT GREEN (-2075 3825);
DISPLAY INVISIBLE (-2075 3825);
FORCEPROP 1 LAST PATH I70
J 2
(-1750 3950);
DISPLAY 0.936170 (-1750 3950);
PAINT GREEN (-1750 3950);
DISPLAY INVISIBLE (-1750 3950);
FORCEADD TAP..6
R 2
(-1750 4050);
FORCEPROP 3 LASTPIN (-1800 4050) SIG_NAME M_D_DQ<40>
J 0
(-1790 4060);
DISPLAY 0.659574 (-1790 4060);
PAINT MONO (-1790 4060);
DISPLAY INVISIBLE (-1790 4060);
FORCEPROP 1 LASTPIN (-1800 4050) BN 40
J 2
(-1750 4060);
DISPLAY 0.617021 (-1750 4060);
PAINT PINK (-1750 4060);
FORCEPROP 2 LAST CDS_LIB mstr_standard
J 2
(-1750 4050);
DISPLAY 0.787234 (-1750 4050);
PAINT MONO (-1750 4050);
DISPLAY INVISIBLE (-1750 4050);
FORCEPROP 1 LAST BODY_TYPE PLUMBING
J 2
(-1750 4000);
DISPLAY 1.234043 (-1750 4000);
PAINT GREEN (-1750 4000);
DISPLAY INVISIBLE (-1750 4000);
FORCEPROP 1 LAST HDL_TAP TRUE
J 2
(-2075 3925);
DISPLAY 1.234043 (-2075 3925);
PAINT GREEN (-2075 3925);
DISPLAY INVISIBLE (-2075 3925);
FORCEPROP 1 LAST PATH I71
J 2
(-1750 4050);
DISPLAY 0.936170 (-1750 4050);
PAINT GREEN (-1750 4050);
DISPLAY INVISIBLE (-1750 4050);
FORCEADD TAP..6
R 2
(-1750 3900);
FORCEPROP 3 LASTPIN (-1800 3900) SIG_NAME M_D_DQ<39>
J 0
(-1790 3910);
DISPLAY 0.659574 (-1790 3910);
PAINT MONO (-1790 3910);
DISPLAY INVISIBLE (-1790 3910);
FORCEPROP 1 LASTPIN (-1800 3900) BN 39
J 2
(-1750 3910);
DISPLAY 0.617021 (-1750 3910);
PAINT PINK (-1750 3910);
FORCEPROP 2 LAST CDS_LIB mstr_standard
J 2
(-1750 3900);
DISPLAY 0.787234 (-1750 3900);
PAINT MONO (-1750 3900);
DISPLAY INVISIBLE (-1750 3900);
FORCEPROP 1 LAST BODY_TYPE PLUMBING
J 2
(-1750 3850);
DISPLAY 1.234043 (-1750 3850);
PAINT GREEN (-1750 3850);
DISPLAY INVISIBLE (-1750 3850);
FORCEPROP 1 LAST HDL_TAP TRUE
J 2
(-2075 3775);
DISPLAY 1.234043 (-2075 3775);
PAINT GREEN (-2075 3775);
DISPLAY INVISIBLE (-2075 3775);
FORCEPROP 1 LAST PATH I72
J 2
(-1750 3900);
DISPLAY 0.936170 (-1750 3900);
PAINT GREEN (-1750 3900);
DISPLAY INVISIBLE (-1750 3900);
FORCEADD TAP..6
R 2
(-1750 3850);
FORCEPROP 3 LASTPIN (-1800 3850) SIG_NAME M_D_DQ<36>
J 0
(-1790 3860);
DISPLAY 0.659574 (-1790 3860);
PAINT MONO (-1790 3860);
DISPLAY INVISIBLE (-1790 3860);
FORCEPROP 1 LASTPIN (-1800 3850) BN 36
J 2
(-1750 3860);
DISPLAY 0.617021 (-1750 3860);
PAINT PINK (-1750 3860);
FORCEPROP 2 LAST CDS_LIB mstr_standard
J 2
(-1750 3850);
DISPLAY 0.787234 (-1750 3850);
PAINT MONO (-1750 3850);
DISPLAY INVISIBLE (-1750 3850);
FORCEPROP 1 LAST BODY_TYPE PLUMBING
J 2
(-1750 3800);
DISPLAY 1.234043 (-1750 3800);
PAINT GREEN (-1750 3800);
DISPLAY INVISIBLE (-1750 3800);
FORCEPROP 1 LAST HDL_TAP TRUE
J 2
(-2075 3725);
DISPLAY 1.234043 (-2075 3725);
PAINT GREEN (-2075 3725);
DISPLAY INVISIBLE (-2075 3725);
FORCEPROP 1 LAST PATH I73
J 2
(-1750 3850);
DISPLAY 0.936170 (-1750 3850);
PAINT GREEN (-1750 3850);
DISPLAY INVISIBLE (-1750 3850);
FORCEADD TAP..6
R 2
(-1750 3800);
FORCEPROP 3 LASTPIN (-1800 3800) SIG_NAME M_D_DQ<37>
J 0
(-1790 3810);
DISPLAY 0.659574 (-1790 3810);
PAINT MONO (-1790 3810);
DISPLAY INVISIBLE (-1790 3810);
FORCEPROP 1 LASTPIN (-1800 3800) BN 37
J 2
(-1750 3810);
DISPLAY 0.617021 (-1750 3810);
PAINT PINK (-1750 3810);
FORCEPROP 2 LAST CDS_LIB mstr_standard
J 2
(-1750 3800);
DISPLAY 0.787234 (-1750 3800);
PAINT MONO (-1750 3800);
DISPLAY INVISIBLE (-1750 3800);
FORCEPROP 1 LAST BODY_TYPE PLUMBING
J 2
(-1750 3750);
DISPLAY 1.234043 (-1750 3750);
PAINT GREEN (-1750 3750);
DISPLAY INVISIBLE (-1750 3750);
FORCEPROP 1 LAST HDL_TAP TRUE
J 2
(-2075 3675);
DISPLAY 1.234043 (-2075 3675);
PAINT GREEN (-2075 3675);
DISPLAY INVISIBLE (-2075 3675);
FORCEPROP 1 LAST PATH I74
J 2
(-1750 3800);
DISPLAY 0.936170 (-1750 3800);
PAINT GREEN (-1750 3800);
DISPLAY INVISIBLE (-1750 3800);
FORCEADD TAP..6
R 2
(-1750 3700);
FORCEPROP 3 LASTPIN (-1800 3700) SIG_NAME M_D_DQ<35>
J 0
(-1790 3710);
DISPLAY 0.659574 (-1790 3710);
PAINT MONO (-1790 3710);
DISPLAY INVISIBLE (-1790 3710);
FORCEPROP 1 LASTPIN (-1800 3700) BN 35
J 2
(-1750 3710);
DISPLAY 0.617021 (-1750 3710);
PAINT PINK (-1750 3710);
FORCEPROP 2 LAST CDS_LIB mstr_standard
J 2
(-1750 3700);
DISPLAY 0.787234 (-1750 3700);
PAINT MONO (-1750 3700);
DISPLAY INVISIBLE (-1750 3700);
FORCEPROP 1 LAST BODY_TYPE PLUMBING
J 2
(-1750 3650);
DISPLAY 1.234043 (-1750 3650);
PAINT GREEN (-1750 3650);
DISPLAY INVISIBLE (-1750 3650);
FORCEPROP 1 LAST HDL_TAP TRUE
J 2
(-2075 3575);
DISPLAY 1.234043 (-2075 3575);
PAINT GREEN (-2075 3575);
DISPLAY INVISIBLE (-2075 3575);
FORCEPROP 1 LAST PATH I75
J 2
(-1750 3700);
DISPLAY 0.936170 (-1750 3700);
PAINT GREEN (-1750 3700);
DISPLAY INVISIBLE (-1750 3700);
FORCEADD TAP..6
R 2
(-1750 3750);
FORCEPROP 3 LASTPIN (-1800 3750) SIG_NAME M_D_DQ<34>
J 0
(-1790 3760);
DISPLAY 0.659574 (-1790 3760);
PAINT MONO (-1790 3760);
DISPLAY INVISIBLE (-1790 3760);
FORCEPROP 1 LASTPIN (-1800 3750) BN 34
J 2
(-1750 3760);
DISPLAY 0.617021 (-1750 3760);
PAINT PINK (-1750 3760);
FORCEPROP 2 LAST CDS_LIB mstr_standard
J 2
(-1750 3750);
DISPLAY 0.787234 (-1750 3750);
PAINT MONO (-1750 3750);
DISPLAY INVISIBLE (-1750 3750);
FORCEPROP 1 LAST BODY_TYPE PLUMBING
J 2
(-1750 3700);
DISPLAY 1.234043 (-1750 3700);
PAINT GREEN (-1750 3700);
DISPLAY INVISIBLE (-1750 3700);
FORCEPROP 1 LAST HDL_TAP TRUE
J 2
(-2075 3625);
DISPLAY 1.234043 (-2075 3625);
PAINT GREEN (-2075 3625);
DISPLAY INVISIBLE (-2075 3625);
FORCEPROP 1 LAST PATH I76
J 2
(-1750 3750);
DISPLAY 0.936170 (-1750 3750);
PAINT GREEN (-1750 3750);
DISPLAY INVISIBLE (-1750 3750);
FORCEADD TAP..6
R 2
(-1750 3650);
FORCEPROP 3 LASTPIN (-1800 3650) SIG_NAME M_D_DQ<32>
J 0
(-1790 3660);
DISPLAY 0.659574 (-1790 3660);
PAINT MONO (-1790 3660);
DISPLAY INVISIBLE (-1790 3660);
FORCEPROP 1 LASTPIN (-1800 3650) BN 32
J 2
(-1750 3660);
DISPLAY 0.617021 (-1750 3660);
PAINT PINK (-1750 3660);
FORCEPROP 2 LAST CDS_LIB mstr_standard
J 2
(-1750 3650);
DISPLAY 0.787234 (-1750 3650);
PAINT MONO (-1750 3650);
DISPLAY INVISIBLE (-1750 3650);
FORCEPROP 1 LAST BODY_TYPE PLUMBING
J 2
(-1750 3600);
DISPLAY 1.234043 (-1750 3600);
PAINT GREEN (-1750 3600);
DISPLAY INVISIBLE (-1750 3600);
FORCEPROP 1 LAST HDL_TAP TRUE
J 2
(-2075 3525);
DISPLAY 1.234043 (-2075 3525);
PAINT GREEN (-2075 3525);
DISPLAY INVISIBLE (-2075 3525);
FORCEPROP 1 LAST PATH I77
J 2
(-1750 3650);
DISPLAY 0.936170 (-1750 3650);
PAINT GREEN (-1750 3650);
DISPLAY INVISIBLE (-1750 3650);
FORCEADD TAP..6
R 2
(-1750 3600);
FORCEPROP 3 LASTPIN (-1800 3600) SIG_NAME M_D_DQ<33>
J 0
(-1790 3610);
DISPLAY 0.659574 (-1790 3610);
PAINT MONO (-1790 3610);
DISPLAY INVISIBLE (-1790 3610);
FORCEPROP 1 LASTPIN (-1800 3600) BN 33
J 2
(-1750 3610);
DISPLAY 0.617021 (-1750 3610);
PAINT PINK (-1750 3610);
FORCEPROP 2 LAST CDS_LIB mstr_standard
J 2
(-1750 3600);
DISPLAY 0.787234 (-1750 3600);
PAINT MONO (-1750 3600);
DISPLAY INVISIBLE (-1750 3600);
FORCEPROP 1 LAST BODY_TYPE PLUMBING
J 2
(-1750 3550);
DISPLAY 1.234043 (-1750 3550);
PAINT GREEN (-1750 3550);
DISPLAY INVISIBLE (-1750 3550);
FORCEPROP 1 LAST HDL_TAP TRUE
J 2
(-2075 3475);
DISPLAY 1.234043 (-2075 3475);
PAINT GREEN (-2075 3475);
DISPLAY INVISIBLE (-2075 3475);
FORCEPROP 1 LAST PATH I78
J 2
(-1750 3600);
DISPLAY 0.936170 (-1750 3600);
PAINT GREEN (-1750 3600);
DISPLAY INVISIBLE (-1750 3600);
FORCEADD TAP..6
R 2
(-1750 3450);
FORCEPROP 3 LASTPIN (-1800 3450) SIG_NAME M_D_DQ<28>
J 0
(-1790 3460);
DISPLAY 0.659574 (-1790 3460);
PAINT MONO (-1790 3460);
DISPLAY INVISIBLE (-1790 3460);
FORCEPROP 1 LASTPIN (-1800 3450) BN 28
J 2
(-1750 3460);
DISPLAY 0.617021 (-1750 3460);
PAINT PINK (-1750 3460);
FORCEPROP 2 LAST CDS_LIB mstr_standard
J 2
(-1750 3450);
DISPLAY 0.787234 (-1750 3450);
PAINT MONO (-1750 3450);
DISPLAY INVISIBLE (-1750 3450);
FORCEPROP 1 LAST BODY_TYPE PLUMBING
J 2
(-1750 3400);
DISPLAY 1.234043 (-1750 3400);
PAINT GREEN (-1750 3400);
DISPLAY INVISIBLE (-1750 3400);
FORCEPROP 1 LAST HDL_TAP TRUE
J 2
(-2075 3325);
DISPLAY 1.234043 (-2075 3325);
PAINT GREEN (-2075 3325);
DISPLAY INVISIBLE (-2075 3325);
FORCEPROP 1 LAST PATH I79
J 2
(-1750 3450);
DISPLAY 0.936170 (-1750 3450);
PAINT GREEN (-1750 3450);
DISPLAY INVISIBLE (-1750 3450);
FORCEADD TAP..6
R 2
(900 4850);
FORCEPROP 3 LASTPIN (850 4850) SIG_NAME M_D_DQS_DN<14>
J 0
(860 4860);
DISPLAY 0.659574 (860 4860);
PAINT MONO (860 4860);
DISPLAY INVISIBLE (860 4860);
FORCEPROP 1 LASTPIN (850 4850) BN 14
J 2
(900 4860);
DISPLAY 0.617021 (900 4860);
PAINT PINK (900 4860);
FORCEPROP 2 LAST CDS_LIB mstr_standard
J 0
(900 4850);
DISPLAY 0.787234 (900 4850);
PAINT MONO (900 4850);
DISPLAY INVISIBLE (900 4850);
FORCEPROP 1 LAST BODY_TYPE PLUMBING
J 2
(900 4800);
DISPLAY 1.234043 (900 4800);
PAINT GREEN (900 4800);
DISPLAY INVISIBLE (900 4800);
FORCEPROP 1 LAST HDL_TAP TRUE
J 2
(575 4725);
DISPLAY 1.234043 (575 4725);
PAINT GREEN (575 4725);
DISPLAY INVISIBLE (575 4725);
FORCEPROP 1 LAST PATH I8
J 2
(900 4850);
DISPLAY 0.936170 (900 4850);
PAINT GREEN (900 4850);
DISPLAY INVISIBLE (900 4850);
FORCEADD TAP..6
R 2
(-1750 3550);
FORCEPROP 3 LASTPIN (-1800 3550) SIG_NAME M_D_DQ<30>
J 0
(-1790 3560);
DISPLAY 0.659574 (-1790 3560);
PAINT MONO (-1790 3560);
DISPLAY INVISIBLE (-1790 3560);
FORCEPROP 1 LASTPIN (-1800 3550) BN 30
J 2
(-1750 3560);
DISPLAY 0.617021 (-1750 3560);
PAINT PINK (-1750 3560);
FORCEPROP 2 LAST CDS_LIB mstr_standard
J 2
(-1750 3550);
DISPLAY 0.787234 (-1750 3550);
PAINT MONO (-1750 3550);
DISPLAY INVISIBLE (-1750 3550);
FORCEPROP 1 LAST BODY_TYPE PLUMBING
J 2
(-1750 3500);
DISPLAY 1.234043 (-1750 3500);
PAINT GREEN (-1750 3500);
DISPLAY INVISIBLE (-1750 3500);
FORCEPROP 1 LAST HDL_TAP TRUE
J 2
(-2075 3425);
DISPLAY 1.234043 (-2075 3425);
PAINT GREEN (-2075 3425);
DISPLAY INVISIBLE (-2075 3425);
FORCEPROP 1 LAST PATH I80
J 2
(-1750 3550);
DISPLAY 0.936170 (-1750 3550);
PAINT GREEN (-1750 3550);
DISPLAY INVISIBLE (-1750 3550);
FORCEADD TAP..6
R 2
(-1750 3500);
FORCEPROP 3 LASTPIN (-1800 3500) SIG_NAME M_D_DQ<31>
J 0
(-1790 3510);
DISPLAY 0.659574 (-1790 3510);
PAINT MONO (-1790 3510);
DISPLAY INVISIBLE (-1790 3510);
FORCEPROP 1 LASTPIN (-1800 3500) BN 31
J 2
(-1750 3510);
DISPLAY 0.617021 (-1750 3510);
PAINT PINK (-1750 3510);
FORCEPROP 2 LAST CDS_LIB mstr_standard
J 2
(-1750 3500);
DISPLAY 0.787234 (-1750 3500);
PAINT MONO (-1750 3500);
DISPLAY INVISIBLE (-1750 3500);
FORCEPROP 1 LAST BODY_TYPE PLUMBING
J 2
(-1750 3450);
DISPLAY 1.234043 (-1750 3450);
PAINT GREEN (-1750 3450);
DISPLAY INVISIBLE (-1750 3450);
FORCEPROP 1 LAST HDL_TAP TRUE
J 2
(-2075 3375);
DISPLAY 1.234043 (-2075 3375);
PAINT GREEN (-2075 3375);
DISPLAY INVISIBLE (-2075 3375);
FORCEPROP 1 LAST PATH I81
J 2
(-1750 3500);
DISPLAY 0.936170 (-1750 3500);
PAINT GREEN (-1750 3500);
DISPLAY INVISIBLE (-1750 3500);
FORCEADD TAP..6
R 2
(-1750 3350);
FORCEPROP 3 LASTPIN (-1800 3350) SIG_NAME M_D_DQ<26>
J 0
(-1790 3360);
DISPLAY 0.659574 (-1790 3360);
PAINT MONO (-1790 3360);
DISPLAY INVISIBLE (-1790 3360);
FORCEPROP 1 LASTPIN (-1800 3350) BN 26
J 2
(-1750 3360);
DISPLAY 0.617021 (-1750 3360);
PAINT PINK (-1750 3360);
FORCEPROP 2 LAST CDS_LIB mstr_standard
J 2
(-1750 3350);
DISPLAY 0.787234 (-1750 3350);
PAINT MONO (-1750 3350);
DISPLAY INVISIBLE (-1750 3350);
FORCEPROP 1 LAST BODY_TYPE PLUMBING
J 2
(-1750 3300);
DISPLAY 1.234043 (-1750 3300);
PAINT GREEN (-1750 3300);
DISPLAY INVISIBLE (-1750 3300);
FORCEPROP 1 LAST HDL_TAP TRUE
J 2
(-2075 3225);
DISPLAY 1.234043 (-2075 3225);
PAINT GREEN (-2075 3225);
DISPLAY INVISIBLE (-2075 3225);
FORCEPROP 1 LAST PATH I82
J 2
(-1750 3350);
DISPLAY 0.936170 (-1750 3350);
PAINT GREEN (-1750 3350);
DISPLAY INVISIBLE (-1750 3350);
FORCEADD TAP..6
R 2
(-1750 3400);
FORCEPROP 3 LASTPIN (-1800 3400) SIG_NAME M_D_DQ<29>
J 0
(-1790 3410);
DISPLAY 0.659574 (-1790 3410);
PAINT MONO (-1790 3410);
DISPLAY INVISIBLE (-1790 3410);
FORCEPROP 1 LASTPIN (-1800 3400) BN 29
J 2
(-1750 3410);
DISPLAY 0.617021 (-1750 3410);
PAINT PINK (-1750 3410);
FORCEPROP 2 LAST CDS_LIB mstr_standard
J 2
(-1750 3400);
DISPLAY 0.787234 (-1750 3400);
PAINT MONO (-1750 3400);
DISPLAY INVISIBLE (-1750 3400);
FORCEPROP 1 LAST BODY_TYPE PLUMBING
J 2
(-1750 3350);
DISPLAY 1.234043 (-1750 3350);
PAINT GREEN (-1750 3350);
DISPLAY INVISIBLE (-1750 3350);
FORCEPROP 1 LAST HDL_TAP TRUE
J 2
(-2075 3275);
DISPLAY 1.234043 (-2075 3275);
PAINT GREEN (-2075 3275);
DISPLAY INVISIBLE (-2075 3275);
FORCEPROP 1 LAST PATH I83
J 2
(-1750 3400);
DISPLAY 0.936170 (-1750 3400);
PAINT GREEN (-1750 3400);
DISPLAY INVISIBLE (-1750 3400);
FORCEADD TAP..6
R 2
(-1750 3300);
FORCEPROP 3 LASTPIN (-1800 3300) SIG_NAME M_D_DQ<27>
J 0
(-1790 3310);
DISPLAY 0.659574 (-1790 3310);
PAINT MONO (-1790 3310);
DISPLAY INVISIBLE (-1790 3310);
FORCEPROP 1 LASTPIN (-1800 3300) BN 27
J 2
(-1750 3310);
DISPLAY 0.617021 (-1750 3310);
PAINT PINK (-1750 3310);
FORCEPROP 2 LAST CDS_LIB mstr_standard
J 2
(-1750 3300);
DISPLAY 0.787234 (-1750 3300);
PAINT MONO (-1750 3300);
DISPLAY INVISIBLE (-1750 3300);
FORCEPROP 1 LAST BODY_TYPE PLUMBING
J 2
(-1750 3250);
DISPLAY 1.234043 (-1750 3250);
PAINT GREEN (-1750 3250);
DISPLAY INVISIBLE (-1750 3250);
FORCEPROP 1 LAST HDL_TAP TRUE
J 2
(-2075 3175);
DISPLAY 1.234043 (-2075 3175);
PAINT GREEN (-2075 3175);
DISPLAY INVISIBLE (-2075 3175);
FORCEPROP 1 LAST PATH I84
J 2
(-1750 3300);
DISPLAY 0.936170 (-1750 3300);
PAINT GREEN (-1750 3300);
DISPLAY INVISIBLE (-1750 3300);
FORCEADD TAP..6
R 2
(-1750 3200);
FORCEPROP 3 LASTPIN (-1800 3200) SIG_NAME M_D_DQ<25>
J 0
(-1790 3210);
DISPLAY 0.659574 (-1790 3210);
PAINT MONO (-1790 3210);
DISPLAY INVISIBLE (-1790 3210);
FORCEPROP 1 LASTPIN (-1800 3200) BN 25
J 2
(-1750 3210);
DISPLAY 0.617021 (-1750 3210);
PAINT PINK (-1750 3210);
FORCEPROP 2 LAST CDS_LIB mstr_standard
J 2
(-1750 3200);
DISPLAY 0.787234 (-1750 3200);
PAINT MONO (-1750 3200);
DISPLAY INVISIBLE (-1750 3200);
FORCEPROP 1 LAST BODY_TYPE PLUMBING
J 2
(-1750 3150);
DISPLAY 1.234043 (-1750 3150);
PAINT GREEN (-1750 3150);
DISPLAY INVISIBLE (-1750 3150);
FORCEPROP 1 LAST HDL_TAP TRUE
J 2
(-2075 3075);
DISPLAY 1.234043 (-2075 3075);
PAINT GREEN (-2075 3075);
DISPLAY INVISIBLE (-2075 3075);
FORCEPROP 1 LAST PATH I85
J 2
(-1750 3200);
DISPLAY 0.936170 (-1750 3200);
PAINT GREEN (-1750 3200);
DISPLAY INVISIBLE (-1750 3200);
FORCEADD TAP..6
R 2
(-1750 3250);
FORCEPROP 3 LASTPIN (-1800 3250) SIG_NAME M_D_DQ<24>
J 0
(-1790 3260);
DISPLAY 0.659574 (-1790 3260);
PAINT MONO (-1790 3260);
DISPLAY INVISIBLE (-1790 3260);
FORCEPROP 1 LASTPIN (-1800 3250) BN 24
J 2
(-1750 3260);
DISPLAY 0.617021 (-1750 3260);
PAINT PINK (-1750 3260);
FORCEPROP 2 LAST CDS_LIB mstr_standard
J 2
(-1750 3250);
DISPLAY 0.787234 (-1750 3250);
PAINT MONO (-1750 3250);
DISPLAY INVISIBLE (-1750 3250);
FORCEPROP 1 LAST BODY_TYPE PLUMBING
J 2
(-1750 3200);
DISPLAY 1.234043 (-1750 3200);
PAINT GREEN (-1750 3200);
DISPLAY INVISIBLE (-1750 3200);
FORCEPROP 1 LAST HDL_TAP TRUE
J 2
(-2075 3125);
DISPLAY 1.234043 (-2075 3125);
PAINT GREEN (-2075 3125);
DISPLAY INVISIBLE (-2075 3125);
FORCEPROP 1 LAST PATH I86
J 2
(-1750 3250);
DISPLAY 0.936170 (-1750 3250);
PAINT GREEN (-1750 3250);
DISPLAY INVISIBLE (-1750 3250);
FORCEADD TAP..6
R 2
(-1750 3100);
FORCEPROP 3 LASTPIN (-1800 3100) SIG_NAME M_D_DQ<23>
J 0
(-1790 3110);
DISPLAY 0.659574 (-1790 3110);
PAINT MONO (-1790 3110);
DISPLAY INVISIBLE (-1790 3110);
FORCEPROP 1 LASTPIN (-1800 3100) BN 23
J 2
(-1750 3110);
DISPLAY 0.617021 (-1750 3110);
PAINT PINK (-1750 3110);
FORCEPROP 2 LAST CDS_LIB mstr_standard
J 2
(-1750 3100);
DISPLAY 0.787234 (-1750 3100);
PAINT MONO (-1750 3100);
DISPLAY INVISIBLE (-1750 3100);
FORCEPROP 1 LAST BODY_TYPE PLUMBING
J 2
(-1750 3050);
DISPLAY 1.234043 (-1750 3050);
PAINT GREEN (-1750 3050);
DISPLAY INVISIBLE (-1750 3050);
FORCEPROP 1 LAST HDL_TAP TRUE
J 2
(-2075 2975);
DISPLAY 1.234043 (-2075 2975);
PAINT GREEN (-2075 2975);
DISPLAY INVISIBLE (-2075 2975);
FORCEPROP 1 LAST PATH I87
J 2
(-1750 3100);
DISPLAY 0.936170 (-1750 3100);
PAINT GREEN (-1750 3100);
DISPLAY INVISIBLE (-1750 3100);
FORCEADD TAP..6
R 2
(-1750 3150);
FORCEPROP 3 LASTPIN (-1800 3150) SIG_NAME M_D_DQ<22>
J 0
(-1790 3160);
DISPLAY 0.659574 (-1790 3160);
PAINT MONO (-1790 3160);
DISPLAY INVISIBLE (-1790 3160);
FORCEPROP 1 LASTPIN (-1800 3150) BN 22
J 2
(-1750 3160);
DISPLAY 0.617021 (-1750 3160);
PAINT PINK (-1750 3160);
FORCEPROP 2 LAST CDS_LIB mstr_standard
J 2
(-1750 3150);
DISPLAY 0.787234 (-1750 3150);
PAINT MONO (-1750 3150);
DISPLAY INVISIBLE (-1750 3150);
FORCEPROP 1 LAST BODY_TYPE PLUMBING
J 2
(-1750 3100);
DISPLAY 1.234043 (-1750 3100);
PAINT GREEN (-1750 3100);
DISPLAY INVISIBLE (-1750 3100);
FORCEPROP 1 LAST HDL_TAP TRUE
J 2
(-2075 3025);
DISPLAY 1.234043 (-2075 3025);
PAINT GREEN (-2075 3025);
DISPLAY INVISIBLE (-2075 3025);
FORCEPROP 1 LAST PATH I88
J 2
(-1750 3150);
DISPLAY 0.936170 (-1750 3150);
PAINT GREEN (-1750 3150);
DISPLAY INVISIBLE (-1750 3150);
FORCEADD TAP..6
R 2
(-1750 3050);
FORCEPROP 3 LASTPIN (-1800 3050) SIG_NAME M_D_DQ<20>
J 0
(-1790 3060);
DISPLAY 0.659574 (-1790 3060);
PAINT MONO (-1790 3060);
DISPLAY INVISIBLE (-1790 3060);
FORCEPROP 1 LASTPIN (-1800 3050) BN 20
J 2
(-1750 3060);
DISPLAY 0.617021 (-1750 3060);
PAINT PINK (-1750 3060);
FORCEPROP 2 LAST CDS_LIB mstr_standard
J 2
(-1750 3050);
DISPLAY 0.787234 (-1750 3050);
PAINT MONO (-1750 3050);
DISPLAY INVISIBLE (-1750 3050);
FORCEPROP 1 LAST BODY_TYPE PLUMBING
J 2
(-1750 3000);
DISPLAY 1.234043 (-1750 3000);
PAINT GREEN (-1750 3000);
DISPLAY INVISIBLE (-1750 3000);
FORCEPROP 1 LAST HDL_TAP TRUE
J 2
(-2075 2925);
DISPLAY 1.234043 (-2075 2925);
PAINT GREEN (-2075 2925);
DISPLAY INVISIBLE (-2075 2925);
FORCEPROP 1 LAST PATH I89
J 2
(-1750 3050);
DISPLAY 0.936170 (-1750 3050);
PAINT GREEN (-1750 3050);
DISPLAY INVISIBLE (-1750 3050);
FORCEADD TAP..6
R 2
(900 4650);
FORCEPROP 3 LASTPIN (850 4650) SIG_NAME M_D_DQS_DN<12>
J 0
(860 4660);
DISPLAY 0.659574 (860 4660);
PAINT MONO (860 4660);
DISPLAY INVISIBLE (860 4660);
FORCEPROP 1 LASTPIN (850 4650) BN 12
J 2
(900 4660);
DISPLAY 0.617021 (900 4660);
PAINT PINK (900 4660);
FORCEPROP 2 LAST CDS_LIB mstr_standard
J 0
(900 4650);
DISPLAY 0.787234 (900 4650);
PAINT MONO (900 4650);
DISPLAY INVISIBLE (900 4650);
FORCEPROP 1 LAST BODY_TYPE PLUMBING
J 2
(900 4600);
DISPLAY 1.234043 (900 4600);
PAINT GREEN (900 4600);
DISPLAY INVISIBLE (900 4600);
FORCEPROP 1 LAST HDL_TAP TRUE
J 2
(575 4525);
DISPLAY 1.234043 (575 4525);
PAINT GREEN (575 4525);
DISPLAY INVISIBLE (575 4525);
FORCEPROP 1 LAST PATH I9
J 2
(900 4650);
DISPLAY 0.936170 (900 4650);
PAINT GREEN (900 4650);
DISPLAY INVISIBLE (900 4650);
FORCEADD TAP..6
R 2
(-1750 3000);
FORCEPROP 3 LASTPIN (-1800 3000) SIG_NAME M_D_DQ<21>
J 0
(-1790 3010);
DISPLAY 0.659574 (-1790 3010);
PAINT MONO (-1790 3010);
DISPLAY INVISIBLE (-1790 3010);
FORCEPROP 1 LASTPIN (-1800 3000) BN 21
J 2
(-1750 3010);
DISPLAY 0.617021 (-1750 3010);
PAINT PINK (-1750 3010);
FORCEPROP 2 LAST CDS_LIB mstr_standard
J 2
(-1750 3000);
DISPLAY 0.787234 (-1750 3000);
PAINT MONO (-1750 3000);
DISPLAY INVISIBLE (-1750 3000);
FORCEPROP 1 LAST BODY_TYPE PLUMBING
J 2
(-1750 2950);
DISPLAY 1.234043 (-1750 2950);
PAINT GREEN (-1750 2950);
DISPLAY INVISIBLE (-1750 2950);
FORCEPROP 1 LAST HDL_TAP TRUE
J 2
(-2075 2875);
DISPLAY 1.234043 (-2075 2875);
PAINT GREEN (-2075 2875);
DISPLAY INVISIBLE (-2075 2875);
FORCEPROP 1 LAST PATH I90
J 2
(-1750 3000);
DISPLAY 0.936170 (-1750 3000);
PAINT GREEN (-1750 3000);
DISPLAY INVISIBLE (-1750 3000);
FORCEADD TAP..6
R 2
(-1750 2950);
FORCEPROP 3 LASTPIN (-1800 2950) SIG_NAME M_D_DQ<18>
J 0
(-1790 2960);
DISPLAY 0.659574 (-1790 2960);
PAINT MONO (-1790 2960);
DISPLAY INVISIBLE (-1790 2960);
FORCEPROP 1 LASTPIN (-1800 2950) BN 18
J 2
(-1750 2960);
DISPLAY 0.617021 (-1750 2960);
PAINT PINK (-1750 2960);
FORCEPROP 2 LAST CDS_LIB mstr_standard
J 2
(-1750 2950);
DISPLAY 0.787234 (-1750 2950);
PAINT MONO (-1750 2950);
DISPLAY INVISIBLE (-1750 2950);
FORCEPROP 1 LAST BODY_TYPE PLUMBING
J 2
(-1750 2900);
DISPLAY 1.234043 (-1750 2900);
PAINT GREEN (-1750 2900);
DISPLAY INVISIBLE (-1750 2900);
FORCEPROP 1 LAST HDL_TAP TRUE
J 2
(-2075 2825);
DISPLAY 1.234043 (-2075 2825);
PAINT GREEN (-2075 2825);
DISPLAY INVISIBLE (-2075 2825);
FORCEPROP 1 LAST PATH I91
J 2
(-1750 2950);
DISPLAY 0.936170 (-1750 2950);
PAINT GREEN (-1750 2950);
DISPLAY INVISIBLE (-1750 2950);
FORCEADD TAP..6
R 2
(-1750 2900);
FORCEPROP 3 LASTPIN (-1800 2900) SIG_NAME M_D_DQ<19>
J 0
(-1790 2910);
DISPLAY 0.659574 (-1790 2910);
PAINT MONO (-1790 2910);
DISPLAY INVISIBLE (-1790 2910);
FORCEPROP 1 LASTPIN (-1800 2900) BN 19
J 2
(-1750 2910);
DISPLAY 0.617021 (-1750 2910);
PAINT PINK (-1750 2910);
FORCEPROP 2 LAST CDS_LIB mstr_standard
J 2
(-1750 2900);
DISPLAY 0.787234 (-1750 2900);
PAINT MONO (-1750 2900);
DISPLAY INVISIBLE (-1750 2900);
FORCEPROP 1 LAST BODY_TYPE PLUMBING
J 2
(-1750 2850);
DISPLAY 1.234043 (-1750 2850);
PAINT GREEN (-1750 2850);
DISPLAY INVISIBLE (-1750 2850);
FORCEPROP 1 LAST HDL_TAP TRUE
J 2
(-2075 2775);
DISPLAY 1.234043 (-2075 2775);
PAINT GREEN (-2075 2775);
DISPLAY INVISIBLE (-2075 2775);
FORCEPROP 1 LAST PATH I92
J 2
(-1750 2900);
DISPLAY 0.936170 (-1750 2900);
PAINT GREEN (-1750 2900);
DISPLAY INVISIBLE (-1750 2900);
FORCEADD TAP..6
R 2
(-1750 2800);
FORCEPROP 3 LASTPIN (-1800 2800) SIG_NAME M_D_DQ<17>
J 0
(-1790 2810);
DISPLAY 0.659574 (-1790 2810);
PAINT MONO (-1790 2810);
DISPLAY INVISIBLE (-1790 2810);
FORCEPROP 1 LASTPIN (-1800 2800) BN 17
J 2
(-1750 2810);
DISPLAY 0.617021 (-1750 2810);
PAINT PINK (-1750 2810);
FORCEPROP 2 LAST CDS_LIB mstr_standard
J 2
(-1750 2800);
DISPLAY 0.787234 (-1750 2800);
PAINT MONO (-1750 2800);
DISPLAY INVISIBLE (-1750 2800);
FORCEPROP 1 LAST BODY_TYPE PLUMBING
J 2
(-1750 2750);
DISPLAY 1.234043 (-1750 2750);
PAINT GREEN (-1750 2750);
DISPLAY INVISIBLE (-1750 2750);
FORCEPROP 1 LAST HDL_TAP TRUE
J 2
(-2075 2675);
DISPLAY 1.234043 (-2075 2675);
PAINT GREEN (-2075 2675);
DISPLAY INVISIBLE (-2075 2675);
FORCEPROP 1 LAST PATH I93
J 2
(-1750 2800);
DISPLAY 0.936170 (-1750 2800);
PAINT GREEN (-1750 2800);
DISPLAY INVISIBLE (-1750 2800);
FORCEADD TAP..6
R 2
(-1750 2850);
FORCEPROP 3 LASTPIN (-1800 2850) SIG_NAME M_D_DQ<16>
J 0
(-1790 2860);
DISPLAY 0.659574 (-1790 2860);
PAINT MONO (-1790 2860);
DISPLAY INVISIBLE (-1790 2860);
FORCEPROP 1 LASTPIN (-1800 2850) BN 16
J 2
(-1750 2860);
DISPLAY 0.617021 (-1750 2860);
PAINT PINK (-1750 2860);
FORCEPROP 2 LAST CDS_LIB mstr_standard
J 2
(-1750 2850);
DISPLAY 0.787234 (-1750 2850);
PAINT MONO (-1750 2850);
DISPLAY INVISIBLE (-1750 2850);
FORCEPROP 1 LAST BODY_TYPE PLUMBING
J 2
(-1750 2800);
DISPLAY 1.234043 (-1750 2800);
PAINT GREEN (-1750 2800);
DISPLAY INVISIBLE (-1750 2800);
FORCEPROP 1 LAST HDL_TAP TRUE
J 2
(-2075 2725);
DISPLAY 1.234043 (-2075 2725);
PAINT GREEN (-2075 2725);
DISPLAY INVISIBLE (-2075 2725);
FORCEPROP 1 LAST PATH I94
J 2
(-1750 2850);
DISPLAY 0.936170 (-1750 2850);
PAINT GREEN (-1750 2850);
DISPLAY INVISIBLE (-1750 2850);
FORCEADD TAP..6
R 2
(-1750 2750);
FORCEPROP 3 LASTPIN (-1800 2750) SIG_NAME M_D_DQ<14>
J 0
(-1790 2760);
DISPLAY 0.659574 (-1790 2760);
PAINT MONO (-1790 2760);
DISPLAY INVISIBLE (-1790 2760);
FORCEPROP 1 LASTPIN (-1800 2750) BN 14
J 2
(-1750 2760);
DISPLAY 0.617021 (-1750 2760);
PAINT PINK (-1750 2760);
FORCEPROP 2 LAST CDS_LIB mstr_standard
J 2
(-1750 2750);
DISPLAY 0.787234 (-1750 2750);
PAINT MONO (-1750 2750);
DISPLAY INVISIBLE (-1750 2750);
FORCEPROP 1 LAST BODY_TYPE PLUMBING
J 2
(-1750 2700);
DISPLAY 1.234043 (-1750 2700);
PAINT GREEN (-1750 2700);
DISPLAY INVISIBLE (-1750 2700);
FORCEPROP 1 LAST HDL_TAP TRUE
J 2
(-2075 2625);
DISPLAY 1.234043 (-2075 2625);
PAINT GREEN (-2075 2625);
DISPLAY INVISIBLE (-2075 2625);
FORCEPROP 1 LAST PATH I95
J 2
(-1750 2750);
DISPLAY 0.936170 (-1750 2750);
PAINT GREEN (-1750 2750);
DISPLAY INVISIBLE (-1750 2750);
FORCEADD TAP..6
R 2
(-1750 2700);
FORCEPROP 3 LASTPIN (-1800 2700) SIG_NAME M_D_DQ<15>
J 0
(-1790 2710);
DISPLAY 0.659574 (-1790 2710);
PAINT MONO (-1790 2710);
DISPLAY INVISIBLE (-1790 2710);
FORCEPROP 1 LASTPIN (-1800 2700) BN 15
J 2
(-1750 2710);
DISPLAY 0.617021 (-1750 2710);
PAINT PINK (-1750 2710);
FORCEPROP 2 LAST CDS_LIB mstr_standard
J 2
(-1750 2700);
DISPLAY 0.787234 (-1750 2700);
PAINT MONO (-1750 2700);
DISPLAY INVISIBLE (-1750 2700);
FORCEPROP 1 LAST BODY_TYPE PLUMBING
J 2
(-1750 2650);
DISPLAY 1.234043 (-1750 2650);
PAINT GREEN (-1750 2650);
DISPLAY INVISIBLE (-1750 2650);
FORCEPROP 1 LAST HDL_TAP TRUE
J 2
(-2075 2575);
DISPLAY 1.234043 (-2075 2575);
PAINT GREEN (-2075 2575);
DISPLAY INVISIBLE (-2075 2575);
FORCEPROP 1 LAST PATH I96
J 2
(-1750 2700);
DISPLAY 0.936170 (-1750 2700);
PAINT GREEN (-1750 2700);
DISPLAY INVISIBLE (-1750 2700);
FORCEADD TAP..6
R 2
(-1750 2600);
FORCEPROP 3 LASTPIN (-1800 2600) SIG_NAME M_D_DQ<13>
J 0
(-1790 2610);
DISPLAY 0.659574 (-1790 2610);
PAINT MONO (-1790 2610);
DISPLAY INVISIBLE (-1790 2610);
FORCEPROP 1 LASTPIN (-1800 2600) BN 13
J 2
(-1750 2610);
DISPLAY 0.617021 (-1750 2610);
PAINT PINK (-1750 2610);
FORCEPROP 2 LAST CDS_LIB mstr_standard
J 2
(-1750 2600);
DISPLAY 0.787234 (-1750 2600);
PAINT MONO (-1750 2600);
DISPLAY INVISIBLE (-1750 2600);
FORCEPROP 1 LAST BODY_TYPE PLUMBING
J 2
(-1750 2550);
DISPLAY 1.234043 (-1750 2550);
PAINT GREEN (-1750 2550);
DISPLAY INVISIBLE (-1750 2550);
FORCEPROP 1 LAST HDL_TAP TRUE
J 2
(-2075 2475);
DISPLAY 1.234043 (-2075 2475);
PAINT GREEN (-2075 2475);
DISPLAY INVISIBLE (-2075 2475);
FORCEPROP 1 LAST PATH I97
J 2
(-1750 2600);
DISPLAY 0.936170 (-1750 2600);
PAINT GREEN (-1750 2600);
DISPLAY INVISIBLE (-1750 2600);
FORCEADD TAP..6
R 2
(-1750 2650);
FORCEPROP 3 LASTPIN (-1800 2650) SIG_NAME M_D_DQ<12>
J 0
(-1790 2660);
DISPLAY 0.659574 (-1790 2660);
PAINT MONO (-1790 2660);
DISPLAY INVISIBLE (-1790 2660);
FORCEPROP 1 LASTPIN (-1800 2650) BN 12
J 2
(-1750 2660);
DISPLAY 0.617021 (-1750 2660);
PAINT PINK (-1750 2660);
FORCEPROP 2 LAST CDS_LIB mstr_standard
J 2
(-1750 2650);
DISPLAY 0.787234 (-1750 2650);
PAINT MONO (-1750 2650);
DISPLAY INVISIBLE (-1750 2650);
FORCEPROP 1 LAST BODY_TYPE PLUMBING
J 2
(-1750 2600);
DISPLAY 1.234043 (-1750 2600);
PAINT GREEN (-1750 2600);
DISPLAY INVISIBLE (-1750 2600);
FORCEPROP 1 LAST HDL_TAP TRUE
J 2
(-2075 2525);
DISPLAY 1.234043 (-2075 2525);
PAINT GREEN (-2075 2525);
DISPLAY INVISIBLE (-2075 2525);
FORCEPROP 1 LAST PATH I98
J 2
(-1750 2650);
DISPLAY 0.936170 (-1750 2650);
PAINT GREEN (-1750 2650);
DISPLAY INVISIBLE (-1750 2650);
FORCEADD TAP..6
R 2
(-1750 2550);
FORCEPROP 3 LASTPIN (-1800 2550) SIG_NAME M_D_DQ<10>
J 0
(-1790 2560);
DISPLAY 0.659574 (-1790 2560);
PAINT MONO (-1790 2560);
DISPLAY INVISIBLE (-1790 2560);
FORCEPROP 1 LASTPIN (-1800 2550) BN 10
J 2
(-1750 2560);
DISPLAY 0.617021 (-1750 2560);
PAINT PINK (-1750 2560);
FORCEPROP 2 LAST CDS_LIB mstr_standard
J 2
(-1750 2550);
DISPLAY 0.787234 (-1750 2550);
PAINT MONO (-1750 2550);
DISPLAY INVISIBLE (-1750 2550);
FORCEPROP 1 LAST BODY_TYPE PLUMBING
J 2
(-1750 2500);
DISPLAY 1.234043 (-1750 2500);
PAINT GREEN (-1750 2500);
DISPLAY INVISIBLE (-1750 2500);
FORCEPROP 1 LAST HDL_TAP TRUE
J 2
(-2075 2425);
DISPLAY 1.234043 (-2075 2425);
PAINT GREEN (-2075 2425);
DISPLAY INVISIBLE (-2075 2425);
FORCEPROP 1 LAST PATH I99
J 2
(-1750 2550);
DISPLAY 0.936170 (-1750 2550);
PAINT GREEN (-1750 2550);
DISPLAY INVISIBLE (-1750 2550);
FORCEADD BOM_NOTE..1
(-5075 5325);
FORCEPROP 0 LAST L1 STUFF FOR SKU A & B
J 0
(-5225 5225);
DISPLAY 1.063830 (-5225 5225);
PAINT WHITE (-5225 5225);
FORCEPROP 2 LAST BOM_COST SB
J 0
(-5225 5300);
DISPLAY 1.361702 (-5225 5300);
PAINT ORANGE (-5225 5300);
DISPLAY INVISIBLE (-5225 5300);
FORCEPROP 2 LAST CDS_LIB mstr_symbols
J 0
(-5075 5325);
PAINT ORANGE (-5075 5325);
DISPLAY INVISIBLE (-5075 5325);
FORCEPROP 1 LAST COMMENT_BODY TRUE
J 0
(-5050 5425);
DISPLAY 1.319149 (-5050 5425);
PAINT ORANGE (-5050 5425);
DISPLAY INVISIBLE (-5050 5425);
FORCEPROP 2 LAST ROOM SB_HEADERS
J 0
(-5225 5300);
DISPLAY 1.361702 (-5225 5300);
PAINT ORANGE (-5225 5300);
DISPLAY INVISIBLE (-5225 5300);
FORCEADD INTEL_CORP_BPAGE..1
(2650 500);
FORCEPROP 1 LAST CDS_CON_LAST_MODIFIED Fri Jun 16 17:48:19 2017
J 0
(1225 825);
DISPLAY 0.787234 (1225 825);
PAINT ORANGE (1225 825);
DISPLAY INVISIBLE (1225 825);
FORCEPROP 1 LAST CUSTOM_TXT_CDS <CURRENT_DESIGN_SHEET> OF <TOTAL_DESIGN_SHEETS>
J 0
(2150 525);
PAINT ORANGE (2150 525);
FORCEPROP 1 LAST CUSTOM_TXT_CDS <CON_LAST_MODIFIED>
J 0
(-1350 600);
PAINT ORANGE (-1350 600);
FORCEPROP 2 LAST CUSTOM_TXT_CDS <XR_PAGE_TITLE>
J 0
(-5240 5750);
DISPLAY 0.638298 (-5240 5750);
PAINT PINK (-5240 5750);
DISPLAY INVISIBLE (-5240 5750);
FORCEPROP 1 LAST SCH_TITLE CPU0 DDR4 CH D DIMM0
J 0
(-5300 550);
DISPLAY 1.212766 (-5300 550);
PAINT WHITE (-5300 550);
FORCEPROP 2 LAST CDS_LIB mstr_symbols
J 0
(2650 500);
DISPLAY 0.787234 (2650 500);
PAINT MONO (2650 500);
DISPLAY INVISIBLE (2650 500);
FORCEPROP 2 LAST PAGE_BORDER TRUE
J 0
(-5240 5750);
DISPLAY 0.680851 (-5240 5750);
PAINT PINK (-5240 5750);
DISPLAY INVISIBLE (-5240 5750);
FORCEPROP 1 LAST COMMENT_BODY TRUE
J 0
(2660 510);
DISPLAY 0.382979 (2660 510);
PAINT GREEN (2660 510);
DISPLAY INVISIBLE (2660 510);
FORCEPROP 2 LAST CDS_XR_PAGE_TITLE CR-49 : @BASEBOARD_FAB2_LIB.BASEBOARD_FAB2(SCH_1):PAGE49
J 0
(-5240 5750);
DISPLAY 0.638298 (-5240 5750);
PAINT PINK (-5240 5750);
DISPLAY INVISIBLE (-5240 5750);
WIRE 16 -1 (-1225 2425)(-1225 2350);
WIRE 16 -1 (-1225 2350)(-750 2350);
WIRE 16 -1 (-750 2300)(-750 2350);
WIRE 16 -1 (-750 2350)(-550 2350);
WIRE 16 -1 (-750 2250)(-750 2300);
WIRE 16 -1 (-750 2300)(-550 2300);
WIRE 16 -1 (-750 2200)(-750 2250);
WIRE 16 -1 (-750 2250)(-550 2250);
WIRE 16 -1 (-750 2150)(-750 2200);
WIRE 16 -1 (-750 2200)(-550 2200);
WIRE 16 -1 (-750 2100)(-750 2150);
WIRE 16 -1 (-750 2150)(-550 2150);
WIRE 16 -1 (-750 2050)(-750 2100);
WIRE 16 -1 (-750 2100)(-550 2100);
WIRE 16 -1 (-750 2000)(-750 2050);
WIRE 16 -1 (-750 2050)(-550 2050);
WIRE 16 -1 (-750 1950)(-750 2000);
WIRE 16 -1 (-750 2000)(-550 2000);
WIRE 16 -1 (-750 1900)(-750 1950);
WIRE 16 -1 (-750 1950)(-550 1950);
WIRE 16 -1 (-750 1850)(-750 1900);
WIRE 16 -1 (-750 1900)(-550 1900);
WIRE 16 -1 (-750 1800)(-750 1850);
WIRE 16 -1 (-750 1850)(-550 1850);
WIRE 16 -1 (-750 1750)(-750 1800);
WIRE 16 -1 (-750 1800)(-550 1800);
WIRE 16 -1 (-750 1700)(-750 1750);
WIRE 16 -1 (-750 1750)(-550 1750);
WIRE 16 -1 (-750 1650)(-750 1700);
WIRE 16 -1 (-750 1700)(-550 1700);
WIRE 16 -1 (-750 1600)(-750 1650);
WIRE 16 -1 (-750 1650)(-550 1650);
WIRE 16 -1 (-750 1550)(-750 1600);
WIRE 16 -1 (-750 1600)(-550 1600);
WIRE 16 -1 (-750 1500)(-750 1550);
WIRE 16 -1 (-750 1550)(-550 1550);
WIRE 16 -1 (-750 1450)(-750 1500);
WIRE 16 -1 (-750 1500)(-550 1500);
WIRE 16 -1 (-750 1400)(-750 1450);
WIRE 16 -1 (-750 1450)(-550 1450);
WIRE 16 -1 (-750 1350)(-750 1400);
WIRE 16 -1 (-750 1400)(-550 1400);
WIRE 16 -1 (-750 1300)(-750 1350);
WIRE 16 -1 (-750 1350)(-550 1350);
WIRE 16 -1 (-750 1250)(-750 1300);
WIRE 16 -1 (-750 1300)(-550 1300);
WIRE 16 -1 (-750 1200)(-750 1250);
WIRE 16 -1 (-750 1250)(-550 1250);
WIRE 16 -1 (-750 1150)(-750 1200);
WIRE 16 -1 (-750 1200)(-550 1200);
WIRE 16 -1 (-750 1100)(-750 1150);
WIRE 16 -1 (-750 1150)(-550 1150);
WIRE 16 -1 (-750 1100)(-550 1100);
WIRE 16 -1 (-925 2600)(-925 2500);
WIRE 16 -1 (-925 2500)(-750 2500);
WIRE 16 -1 (-750 2450)(-750 2500);
WIRE 16 -1 (-750 2500)(-550 2500);
WIRE 16 -1 (-750 2450)(-550 2450);
WIRE 16 -1 (2500 1300)(2500 1200);
WIRE 16 -1 (2500 1300)(2500 1350);
WIRE 16 -1 (2500 1300)(2300 1300);
WIRE 16 -1 (2500 1350)(2500 1400);
WIRE 16 -1 (2300 1350)(2500 1350);
WIRE 16 -1 (2500 1400)(2500 1450);
WIRE 16 -1 (2500 1400)(2300 1400);
WIRE 16 -1 (2500 1450)(2500 1500);
WIRE 16 -1 (2500 1450)(2300 1450);
WIRE 16 -1 (2500 1500)(2500 1550);
WIRE 16 -1 (2300 1500)(2500 1500);
WIRE 16 -1 (2500 1550)(2500 1600);
WIRE 16 -1 (2500 1550)(2300 1550);
WIRE 16 -1 (2500 1600)(2500 1650);
WIRE 16 -1 (2300 1600)(2500 1600);
WIRE 16 -1 (2500 1650)(2500 1700);
WIRE 16 -1 (2500 1650)(2300 1650);
WIRE 16 -1 (2500 1700)(2500 1750);
WIRE 16 -1 (2500 1700)(2300 1700);
WIRE 16 -1 (2500 1750)(2500 1800);
WIRE 16 -1 (2500 1750)(2300 1750);
WIRE 16 -1 (2500 1800)(2500 1850);
WIRE 16 -1 (2300 1800)(2500 1800);
WIRE 16 -1 (2500 1850)(2500 1900);
WIRE 16 -1 (2300 1850)(2500 1850);
WIRE 16 -1 (2500 1900)(2500 1950);
WIRE 16 -1 (2500 1900)(2300 1900);
WIRE 16 -1 (2500 1950)(2500 2000);
WIRE 16 -1 (2300 1950)(2500 1950);
WIRE 16 -1 (2500 2000)(2500 2050);
WIRE 16 -1 (2500 2000)(2300 2000);
WIRE 16 -1 (2500 2050)(2500 2100);
WIRE 16 -1 (2300 2050)(2500 2050);
WIRE 16 -1 (2500 2100)(2500 2150);
WIRE 16 -1 (2500 2100)(2300 2100);
WIRE 16 -1 (2500 2150)(2500 2200);
WIRE 16 -1 (2300 2150)(2500 2150);
WIRE 16 -1 (2500 2200)(2500 2250);
WIRE 16 -1 (2500 2200)(2300 2200);
WIRE 16 -1 (2500 2250)(2500 2300);
WIRE 16 -1 (2500 2250)(2300 2250);
WIRE 16 -1 (2500 2300)(2500 2350);
WIRE 16 -1 (2300 2300)(2500 2300);
WIRE 16 -1 (2500 2350)(2500 2400);
WIRE 16 -1 (2500 2350)(2300 2350);
WIRE 16 -1 (2500 2400)(2500 2450);
WIRE 16 -1 (2300 2400)(2500 2400);
WIRE 16 -1 (2500 2450)(2500 2500);
WIRE 16 -1 (2500 2450)(2300 2450);
WIRE 16 -1 (2500 2500)(2500 2550);
WIRE 16 -1 (2300 2500)(2500 2500);
WIRE 16 -1 (2500 2550)(2500 2600);
WIRE 16 -1 (2500 2550)(2300 2550);
WIRE 16 -1 (2500 2600)(2500 2650);
WIRE 16 -1 (2300 2600)(2500 2600);
WIRE 16 -1 (2500 2650)(2500 2700);
WIRE 16 -1 (2500 2650)(2300 2650);
WIRE 16 -1 (2500 2700)(2500 2750);
WIRE 16 -1 (2300 2700)(2500 2700);
WIRE 16 -1 (2500 2750)(2500 2800);
WIRE 16 -1 (2500 2750)(2300 2750);
WIRE 16 -1 (2500 2800)(2500 2850);
WIRE 16 -1 (2300 2800)(2500 2800);
WIRE 16 -1 (2500 2850)(2500 2900);
WIRE 16 -1 (2500 2850)(2300 2850);
WIRE 16 -1 (2500 2900)(2500 2950);
WIRE 16 -1 (2300 2900)(2500 2900);
WIRE 16 -1 (2500 2950)(2500 3000);
WIRE 16 -1 (2500 2950)(2300 2950);
WIRE 16 -1 (2500 3000)(2500 3050);
WIRE 16 -1 (2300 3000)(2500 3000);
WIRE 16 -1 (2500 3050)(2500 3100);
WIRE 16 -1 (2500 3050)(2300 3050);
WIRE 16 -1 (2500 3100)(2500 3150);
WIRE 16 -1 (2300 3100)(2500 3100);
WIRE 16 -1 (2500 3150)(2500 3200);
WIRE 16 -1 (2500 3150)(2300 3150);
WIRE 16 -1 (2500 3200)(2500 3250);
WIRE 16 -1 (2300 3200)(2500 3200);
WIRE 16 -1 (2500 3250)(2500 3300);
WIRE 16 -1 (2500 3250)(2300 3250);
WIRE 16 -1 (2500 3300)(2500 3350);
WIRE 16 -1 (2300 3300)(2500 3300);
WIRE 16 -1 (2500 3350)(2500 3400);
WIRE 16 -1 (2500 3350)(2300 3350);
WIRE 16 -1 (2500 3400)(2500 3450);
WIRE 16 -1 (2300 3400)(2500 3400);
WIRE 16 -1 (2500 3450)(2500 3500);
WIRE 16 -1 (2500 3450)(2300 3450);
WIRE 16 -1 (2500 3500)(2500 3550);
WIRE 16 -1 (2300 3500)(2500 3500);
WIRE 16 -1 (2500 3550)(2500 3600);
WIRE 16 -1 (2500 3550)(2300 3550);
WIRE 16 -1 (2500 3600)(2300 3600);
WIRE 16 -1 (-5100 2200)(-5100 2150);
WIRE 16 -1 (-3300 2200)(-5100 2200);
FORCEPROP 2 LAST BOM_COST TBD
J 0
(-3650 2250);
PAINT ORANGE (-3650 2250);
DISPLAY INVISIBLE (-3650 2250);
FORCEPROP 2 LAST ROOM TBD
J 0
(-3650 2250);
PAINT ORANGE (-3650 2250);
DISPLAY INVISIBLE (-3650 2250);
WIRE 16 -1 (-3300 2250)(-3300 2200);
WIRE 16 -1 (-3000 2200)(-3300 2200);
WIRE 16 -1 (-3300 2300)(-3300 2250);
WIRE 16 -1 (-3300 2250)(-3000 2250);
WIRE 16 -1 (-3300 2300)(-3000 2300);
WIRE 16 -1 (-4650 1700)(-4650 1600);
WIRE 16 -1 (-750 2900)(-750 2800);
WIRE 16 -1 (-750 2800)(-750 2750);
WIRE 16 -1 (-750 2800)(-550 2800);
WIRE 16 -1 (-750 2750)(-750 2700);
WIRE 16 -1 (-750 2750)(-550 2750);
WIRE 16 -1 (-750 2700)(-750 2650);
WIRE 16 -1 (-550 2700)(-750 2700);
WIRE 16 -1 (-750 2650)(-750 2600);
WIRE 16 -1 (-750 2650)(-550 2650);
WIRE 16 -1 (-750 2600)(-550 2600);
WIRE 16 -1 (-5100 2450)(-5100 2350);
WIRE 16 -1 (-3000 2350)(-5100 2350);
WIRE 16 -1 (650 2800)(650 2975);
WIRE 16 -1 (650 2750)(650 2800);
WIRE 16 -1 (450 2800)(650 2800);
WIRE 16 -1 (450 2750)(650 2750);
WIRE 16 -1 (1100 1300)(1100 1200);
WIRE 16 -1 (1100 1300)(1100 1350);
WIRE 16 -1 (1100 1300)(1300 1300);
WIRE 16 -1 (1100 1350)(1100 1400);
WIRE 16 -1 (1300 1350)(1100 1350);
WIRE 16 -1 (1100 1400)(1100 1450);
WIRE 16 -1 (1100 1400)(1300 1400);
WIRE 16 -1 (1100 1450)(1100 1500);
WIRE 16 -1 (1100 1450)(1300 1450);
WIRE 16 -1 (1100 1500)(1100 1550);
WIRE 16 -1 (1300 1500)(1100 1500);
WIRE 16 -1 (1100 1550)(1100 1600);
WIRE 16 -1 (1100 1550)(1300 1550);
WIRE 16 -1 (1100 1600)(1100 1650);
WIRE 16 -1 (1300 1600)(1100 1600);
WIRE 16 -1 (1100 1650)(1100 1700);
WIRE 16 -1 (1100 1650)(1300 1650);
WIRE 16 -1 (1100 1700)(1100 1750);
WIRE 16 -1 (1100 1700)(1300 1700);
WIRE 16 -1 (1100 1750)(1100 1800);
WIRE 16 -1 (1100 1750)(1300 1750);
WIRE 16 -1 (1100 1800)(1100 1850);
WIRE 16 -1 (1300 1800)(1100 1800);
WIRE 16 -1 (1100 1850)(1100 1900);
WIRE 16 -1 (1300 1850)(1100 1850);
WIRE 16 -1 (1100 1900)(1100 1950);
WIRE 16 -1 (1100 1900)(1300 1900);
WIRE 16 -1 (1100 1950)(1100 2000);
WIRE 16 -1 (1300 1950)(1100 1950);
WIRE 16 -1 (1100 2000)(1100 2050);
WIRE 16 -1 (1100 2000)(1300 2000);
WIRE 16 -1 (1100 2050)(1100 2100);
WIRE 16 -1 (1300 2050)(1100 2050);
WIRE 16 -1 (1100 2100)(1100 2150);
WIRE 16 -1 (1100 2100)(1300 2100);
WIRE 16 -1 (1100 2150)(1100 2200);
WIRE 16 -1 (1300 2150)(1100 2150);
WIRE 16 -1 (1100 2200)(1100 2250);
WIRE 16 -1 (1100 2200)(1300 2200);
WIRE 16 -1 (1100 2250)(1100 2300);
WIRE 16 -1 (1100 2250)(1300 2250);
WIRE 16 -1 (1100 2300)(1100 2350);
WIRE 16 -1 (1300 2300)(1100 2300);
WIRE 16 -1 (1100 2350)(1100 2400);
WIRE 16 -1 (1100 2350)(1300 2350);
WIRE 16 -1 (1100 2400)(1100 2450);
WIRE 16 -1 (1300 2400)(1100 2400);
WIRE 16 -1 (1100 2450)(1100 2500);
WIRE 16 -1 (1100 2450)(1300 2450);
WIRE 16 -1 (1100 2500)(1100 2550);
WIRE 16 -1 (1300 2500)(1100 2500);
WIRE 16 -1 (1100 2550)(1100 2600);
WIRE 16 -1 (1100 2550)(1300 2550);
WIRE 16 -1 (1100 2600)(1100 2650);
WIRE 16 -1 (1300 2600)(1100 2600);
WIRE 16 -1 (1100 2650)(1100 2700);
WIRE 16 -1 (1100 2650)(1300 2650);
WIRE 16 -1 (1100 2700)(1100 2750);
WIRE 16 -1 (1300 2700)(1100 2700);
WIRE 16 -1 (1100 2750)(1100 2800);
WIRE 16 -1 (1100 2750)(1300 2750);
WIRE 16 -1 (1100 2800)(1100 2850);
WIRE 16 -1 (1300 2800)(1100 2800);
WIRE 16 -1 (1100 2850)(1100 2900);
WIRE 16 -1 (1100 2850)(1300 2850);
WIRE 16 -1 (1100 2900)(1100 2950);
WIRE 16 -1 (1300 2900)(1100 2900);
WIRE 16 -1 (1100 2950)(1100 3000);
WIRE 16 -1 (1100 2950)(1300 2950);
WIRE 16 -1 (1100 3000)(1100 3050);
WIRE 16 -1 (1300 3000)(1100 3000);
WIRE 16 -1 (1100 3050)(1100 3100);
WIRE 16 -1 (1100 3050)(1300 3050);
WIRE 16 -1 (1100 3100)(1100 3150);
WIRE 16 -1 (1300 3100)(1100 3100);
WIRE 16 -1 (1100 3150)(1100 3200);
WIRE 16 -1 (1100 3150)(1300 3150);
WIRE 16 -1 (1100 3200)(1100 3250);
WIRE 16 -1 (1300 3200)(1100 3200);
WIRE 16 -1 (1100 3250)(1100 3300);
WIRE 16 -1 (1100 3250)(1300 3250);
WIRE 16 -1 (1100 3300)(1100 3350);
WIRE 16 -1 (1300 3300)(1100 3300);
WIRE 16 -1 (1100 3350)(1100 3400);
WIRE 16 -1 (1100 3350)(1300 3350);
WIRE 16 -1 (1100 3400)(1100 3450);
WIRE 16 -1 (1300 3400)(1100 3400);
WIRE 16 -1 (1100 3450)(1100 3500);
WIRE 16 -1 (1100 3450)(1300 3450);
WIRE 16 -1 (1100 3500)(1100 3550);
WIRE 16 -1 (1300 3500)(1100 3500);
WIRE 16 -1 (1100 3550)(1100 3600);
WIRE 16 -1 (1100 3550)(1300 3550);
WIRE 16 -1 (1100 3600)(1300 3600);
WIRE 17 -1 (950 3475)(950 3575);
WIRE 17 -1 (950 3575)(950 3675);
WIRE 17 -1 (950 3675)(950 3775);
WIRE 17 -1 (950 3775)(950 3875);
WIRE 17 -1 (950 3875)(950 3975);
WIRE 17 -1 (950 3975)(950 4075);
WIRE 17 -1 (950 4075)(950 4175);
WIRE 17 -1 (950 4175)(950 4275);
WIRE 17 -1 (950 4275)(950 4375);
WIRE 17 -1 (950 4375)(950 4475);
WIRE 17 -1 (950 4475)(950 4575);
WIRE 17 -1 (950 4575)(950 4675);
WIRE 17 -1 (950 4675)(950 4775);
WIRE 17 -1 (950 4775)(950 4875);
WIRE 17 -1 (950 4875)(950 4975);
WIRE 17 -1 (950 4975)(950 5075);
WIRE 17 -1 (1600 5200)(950 5200);
FORCEPROP 2 LAST SIG_NAME M_D_DQS_DN<17:0>
J 0
(1000 5210);
DISPLAY 0.617021 (1000 5210);
PAINT ORANGE (1000 5210);
WIRE 17 -1 (950 5075)(950 5175);
WIRE 17 -1 (950 5175)(950 5200);
WIRE 17 -1 (700 3525)(700 3625);
WIRE 17 -1 (700 3625)(700 3725);
WIRE 17 -1 (700 3725)(700 3825);
WIRE 17 -1 (700 3825)(700 3925);
WIRE 17 -1 (700 3925)(700 4025);
WIRE 17 -1 (700 4025)(700 4125);
WIRE 17 -1 (700 4125)(700 4225);
WIRE 17 -1 (700 4225)(700 4325);
WIRE 17 -1 (700 4325)(700 4425);
WIRE 17 -1 (700 4425)(700 4525);
WIRE 17 -1 (700 4525)(700 4625);
WIRE 17 -1 (700 4625)(700 4725);
WIRE 17 -1 (700 4725)(700 4825);
WIRE 17 -1 (700 4825)(700 4925);
WIRE 17 -1 (700 4925)(700 5025);
WIRE 17 -1 (1600 5250)(700 5250);
FORCEPROP 2 LAST SIG_NAME M_D_DQS_DP<17:0>
J 0
(1000 5260);
DISPLAY 0.617021 (1000 5260);
PAINT ORANGE (1000 5260);
WIRE 17 -1 (700 5225)(700 5250);
WIRE 17 -1 (700 5025)(700 5125);
WIRE 17 -1 (700 5125)(700 5225);
WIRE 17 -1 (-1700 2025)(-1700 2075);
WIRE 17 -1 (-1700 2075)(-1700 2125);
WIRE 17 -1 (-1700 2125)(-1700 2175);
WIRE 17 -1 (-1700 2175)(-1700 2225);
WIRE 17 -1 (-1700 2225)(-1700 2275);
WIRE 17 -1 (-1700 2275)(-1700 2325);
WIRE 17 -1 (-1700 2325)(-1700 2375);
WIRE 17 -1 (-1700 2375)(-1700 2425);
WIRE 17 -1 (-1700 2425)(-1700 2475);
WIRE 17 -1 (-1700 2475)(-1700 2525);
WIRE 17 -1 (-1700 2525)(-1700 2575);
WIRE 17 -1 (-1700 2575)(-1700 2625);
WIRE 17 -1 (-1700 2625)(-1700 2675);
WIRE 17 -1 (-1700 2675)(-1700 2725);
WIRE 17 -1 (-1700 2725)(-1700 2775);
WIRE 17 -1 (-1700 2775)(-1700 2825);
WIRE 17 -1 (-1700 2825)(-1700 2875);
WIRE 17 -1 (-1700 2875)(-1700 2925);
WIRE 17 -1 (-1700 2925)(-1700 2975);
WIRE 17 -1 (-1700 2975)(-1700 3025);
WIRE 17 -1 (-1700 3025)(-1700 3075);
WIRE 17 -1 (-1700 3075)(-1700 3125);
WIRE 17 -1 (-1700 3125)(-1700 3175);
WIRE 17 -1 (-1700 3175)(-1700 3225);
WIRE 17 -1 (-1700 3225)(-1700 3275);
WIRE 17 -1 (-1700 3275)(-1700 3325);
WIRE 17 -1 (-1700 3325)(-1700 3375);
WIRE 17 -1 (-1700 3375)(-1700 3425);
WIRE 17 -1 (-1700 3425)(-1700 3475);
WIRE 17 -1 (-1700 3475)(-1700 3525);
WIRE 17 -1 (-1700 3525)(-1700 3575);
WIRE 17 -1 (-1700 3575)(-1700 3625);
WIRE 17 -1 (-1700 3625)(-1700 3675);
WIRE 17 -1 (-1700 3675)(-1700 3725);
WIRE 17 -1 (-1700 3725)(-1700 3775);
WIRE 17 -1 (-1700 3775)(-1700 3825);
WIRE 17 -1 (-1700 3825)(-1700 3875);
WIRE 17 -1 (-1700 3875)(-1700 3925);
WIRE 17 -1 (-1700 3925)(-1700 3975);
WIRE 17 -1 (-1700 3975)(-1700 4025);
WIRE 17 -1 (-1700 4025)(-1700 4075);
WIRE 17 -1 (-1700 4075)(-1700 4125);
WIRE 17 -1 (-1700 4125)(-1700 4175);
WIRE 17 -1 (-1700 4175)(-1700 4225);
WIRE 17 -1 (-1700 4225)(-1700 4275);
WIRE 17 -1 (-1700 4275)(-1700 4325);
WIRE 17 -1 (-1700 4325)(-1700 4375);
WIRE 17 -1 (-1700 4375)(-1700 4425);
WIRE 17 -1 (-1700 4425)(-1700 4475);
WIRE 17 -1 (-1700 4475)(-1700 4525);
WIRE 17 -1 (-1700 4525)(-1700 4575);
WIRE 17 -1 (-1700 4575)(-1700 4625);
WIRE 17 -1 (-1700 4625)(-1700 4675);
WIRE 17 -1 (-1700 4675)(-1700 4725);
WIRE 17 -1 (-1700 4725)(-1700 4775);
WIRE 17 -1 (-1700 4775)(-1700 4825);
WIRE 17 -1 (-1700 4825)(-1700 4875);
WIRE 17 -1 (-1700 4875)(-1700 4925);
WIRE 17 -1 (-1700 4925)(-1700 4975);
WIRE 17 -1 (-1700 4975)(-1700 5025);
WIRE 17 -1 (-1700 5025)(-1700 5075);
WIRE 17 -1 (-1700 5075)(-1700 5125);
WIRE 17 -1 (-1250 5200)(-1700 5200);
FORCEPROP 2 LAST SIG_NAME M_D_DQ<63:0>
J 0
(-1660 5210);
DISPLAY 0.617021 (-1660 5210);
PAINT ORANGE (-1660 5210);
WIRE 17 -1 (-1700 5125)(-1700 5175);
WIRE 17 -1 (-1700 5175)(-1700 5200);
WIRE 17 -1 (-3300 4075)(-3300 4125);
WIRE 17 -1 (-3950 4150)(-3300 4150);
FORCEPROP 2 LAST SIG_NAME M_D_BG<1:0>
J 0
(-3925 4160);
DISPLAY 0.617021 (-3925 4160);
PAINT ORANGE (-3925 4160);
WIRE 17 -1 (-3300 4150)(-3300 4125);
WIRE 17 -1 (-3300 4175)(-3300 4225);
WIRE 17 -1 (-3300 4250)(-3950 4250);
FORCEPROP 2 LAST SIG_NAME M_D_BA<1:0>
J 0
(-3925 4260);
DISPLAY 0.617021 (-3925 4260);
PAINT ORANGE (-3925 4260);
WIRE 17 -1 (-3300 4250)(-3300 4225);
WIRE 17 -1 (-3950 5200)(-3300 5200);
FORCEPROP 2 LAST SIG_NAME M_D_MA<17:0>
J 0
(-3925 5210);
DISPLAY 0.617021 (-3925 5210);
PAINT ORANGE (-3925 5210);
WIRE 17 -1 (-3300 5175)(-3300 5200);
WIRE 17 -1 (-3300 5125)(-3300 5175);
WIRE 17 -1 (-3300 5075)(-3300 5125);
WIRE 17 -1 (-3300 5025)(-3300 5075);
WIRE 17 -1 (-3300 4975)(-3300 5025);
WIRE 17 -1 (-3300 4925)(-3300 4975);
WIRE 17 -1 (-3300 4875)(-3300 4925);
WIRE 17 -1 (-3300 4825)(-3300 4875);
WIRE 17 -1 (-3300 4775)(-3300 4825);
WIRE 17 -1 (-3300 4725)(-3300 4775);
WIRE 17 -1 (-3300 4675)(-3300 4725);
WIRE 17 -1 (-3300 4625)(-3300 4675);
WIRE 17 -1 (-3300 4575)(-3300 4625);
WIRE 17 -1 (-3300 4525)(-3300 4575);
WIRE 17 -1 (-3300 4475)(-3300 4525);
WIRE 17 -1 (-3300 4425)(-3300 4475);
WIRE 17 -1 (-3300 4375)(-3300 4425);
WIRE 17 -1 (-3300 4325)(-3300 4375);
WIRE 17 -1 (-3300 4000)(-3950 4000);
FORCEPROP 2 LAST SIG_NAME M_D_CLK_DP<3:0>
J 0
(-3900 4010);
DISPLAY 0.617021 (-3900 4010);
PAINT ORANGE (-3900 4010);
WIRE 17 -1 (-3300 4000)(-3300 3975);
WIRE 17 -1 (-3300 3875)(-3300 3975);
WIRE 17 -1 (-3500 3925)(-3500 3825);
WIRE 17 -1 (-3500 3950)(-3950 3950);
FORCEPROP 2 LAST SIG_NAME M_D_CLK_DN<3:0>
J 0
(-3900 3960);
DISPLAY 0.617021 (-3900 3960);
PAINT ORANGE (-3900 3960);
WIRE 17 -1 (-3500 3950)(-3500 3925);
WIRE 17 -1 (-3300 3450)(-3950 3450);
FORCEPROP 2 LAST SIG_NAME M_D_CKE<3:0>
J 0
(-3925 3460);
DISPLAY 0.617021 (-3925 3460);
PAINT ORANGE (-3925 3460);
WIRE 17 -1 (-3300 3425)(-3300 3450);
WIRE 17 -1 (-3300 3375)(-3300 3425);
WIRE 17 -1 (-3300 3525)(-3300 3575);
WIRE 17 -1 (-3300 3575)(-3300 3625);
WIRE 17 -1 (-3300 3625)(-3300 3675);
WIRE 17 -1 (-3300 3700)(-3950 3700);
FORCEPROP 2 LAST SIG_NAME M_D_CS_N<7:0>
J 0
(-3925 3710);
DISPLAY 0.617021 (-3925 3710);
PAINT ORANGE (-3925 3710);
WIRE 17 -1 (-3300 3700)(-3300 3675);
WIRE 17 -1 (-3300 2775)(-3300 2825);
WIRE 17 -1 (-3300 2825)(-3300 2875);
WIRE 17 -1 (-3300 2875)(-3300 2925);
WIRE 17 -1 (-3300 2925)(-3300 2975);
WIRE 17 -1 (-3300 2975)(-3300 3025);
WIRE 17 -1 (-3300 3150)(-3950 3150);
FORCEPROP 2 LAST SIG_NAME M_D_ECC<7:0>
J 0
(-3925 3160);
DISPLAY 0.617021 (-3925 3160);
PAINT ORANGE (-3925 3160);
WIRE 17 -1 (-3300 3125)(-3300 3150);
WIRE 17 -1 (-3300 3025)(-3300 3075);
WIRE 17 -1 (-3300 3075)(-3300 3125);
WIRE 17 -1 (-3300 3300)(-3950 3300);
FORCEPROP 2 LAST SIG_NAME M_D_ODT<3:0>
J 0
(-3925 3310);
DISPLAY 0.617021 (-3925 3310);
PAINT ORANGE (-3925 3310);
WIRE 17 -1 (-3300 3275)(-3300 3300);
WIRE 17 -1 (-3300 3225)(-3300 3275);
WIRE 16 -1 (-3850 1800)(-3000 1800);
FORCEPROP 2 LAST SIG_NAME TP_CH_D_DIMM_D0_RFU_0
J 0
(-3800 1810);
DISPLAY 0.617021 (-3800 1810);
PAINT ORANGE (-3800 1810);
FORCEPROP 2 LASTPROP $XRERR UNIQUE?
J 0
(-4090 1800);
DISPLAY 0.638298 (-4090 1800);
PAINT MONO (-4090 1800);
DISPLAY INVISIBLE (-4090 1800);
WIRE 16 -1 (-3850 1850)(-3000 1850);
FORCEPROP 2 LAST SIG_NAME TP_CH_D_DIMM_D0_RFU_1
J 0
(-3800 1860);
DISPLAY 0.617021 (-3800 1860);
PAINT ORANGE (-3800 1860);
FORCEPROP 2 LASTPROP $XRERR UNIQUE?
J 0
(-4090 1850);
DISPLAY 0.638298 (-4090 1850);
PAINT MONO (-4090 1850);
DISPLAY INVISIBLE (-4090 1850);
WIRE 16 -1 (-3850 1900)(-3000 1900);
FORCEPROP 2 LAST SIG_NAME TP_CH_D_DIMM_D0_RFU_2
J 0
(-3800 1910);
DISPLAY 0.617021 (-3800 1910);
PAINT ORANGE (-3800 1910);
FORCEPROP 2 LASTPROP $XRERR UNIQUE?
J 0
(-4090 1900);
DISPLAY 0.638298 (-4090 1900);
PAINT MONO (-4090 1900);
DISPLAY INVISIBLE (-4090 1900);
WIRE 16 -1 (-4750 2000)(-4650 2000);
WIRE 16 -1 (-4650 1900)(-4650 2000);
WIRE 16 -1 (-3000 2000)(-4650 2000);
FORCEPROP 2 LAST SIG_NAME M_D_VREF
J 0
(-3750 2010);
DISPLAY 0.617021 (-3750 2010);
PAINT ORANGE (-3750 2010);
WIRE 16 -1 (-3800 2100)(-3000 2100);
FORCEPROP 2 LAST SIG_NAME SMB_DDR_DEF_VPP_SCL
J 0
(-3760 2110);
DISPLAY 0.617021 (-3760 2110);
PAINT ORANGE (-3760 2110);
WIRE 16 -1 (-3000 2150)(-3800 2150);
WIRE 16 -1 (-3850 1700)(-3000 1700);
FORCEPROP 2 LAST SIG_NAME FM_ADR_COMPLETE_DEF_N
J 0
(-3800 1710);
DISPLAY 0.617021 (-3800 1710);
PAINT ORANGE (-3800 1710);
WIRE 16 -1 (-3000 2450)(-3950 2450);
FORCEPROP 2 LAST SIG_NAME M_D_ACT_N
J 0
(-3900 2460);
DISPLAY 0.617021 (-3900 2460);
PAINT ORANGE (-3900 2460);
WIRE 16 -1 (850 4150)(400 4150);
WIRE 16 -1 (-3000 4900)(-3200 4900);
WIRE 16 -1 (-1800 2350)(-2000 2350);
WIRE 16 -1 (-3000 4050)(-3200 4050);
WIRE 16 -1 (-3000 4350)(-3200 4350);
WIRE 16 -1 (-3000 4500)(-3200 4500);
WIRE 16 -1 (-3000 4600)(-3200 4600);
WIRE 16 -1 (-3000 4650)(-3200 4650);
WIRE 16 -1 (-3000 4700)(-3200 4700);
WIRE 16 -1 (-3000 4750)(-3200 4750);
WIRE 16 -1 (-3000 4800)(-3200 4800);
WIRE 16 -1 (-3000 4850)(-3200 4850);
WIRE 16 -1 (-3000 5050)(-3200 5050);
WIRE 16 -1 (-3000 5100)(-3200 5100);
WIRE 16 -1 (-1800 4900)(-2000 4900);
WIRE 16 -1 (600 4700)(400 4700);
WIRE 16 -1 (-3450 2850)(-4175 2850);
FORCEPROP 2 LAST SIG_NAME FM_DIMM_EVENT_COD_N
J 0
(-4169 2870);
DISPLAY 0.617021 (-4169 2870);
PAINT ORANGE (-4169 2870);
WIRE 16 -1 (-3450 2550)(-3450 2850);
WIRE 16 -1 (-3450 2550)(-3000 2550);
WIRE 16 -1 (-3400 3050)(-3950 3050);
FORCEPROP 2 LAST SIG_NAME M_DEF_RST_N
J 0
(-3925 3060);
DISPLAY 0.617021 (-3925 3060);
PAINT ORANGE (-3925 3060);
WIRE 16 -1 (-3400 2600)(-3400 3050);
WIRE 16 -1 (-3000 2600)(-3400 2600);
WIRE 16 -1 (-3350 3100)(-3950 3100);
FORCEPROP 2 LAST SIG_NAME M_D_PAR
J 0
(-3925 3110);
DISPLAY 0.617021 (-3925 3110);
PAINT ORANGE (-3925 3110);
WIRE 16 -1 (-3350 2650)(-3350 3100);
WIRE 16 -1 (-3000 2650)(-3350 2650);
WIRE 16 -1 (-3150 3750)(-3950 3750);
FORCEPROP 2 LAST SIG_NAME M_D_C<2>
J 0
(-3925 3760);
DISPLAY 0.617021 (-3925 3760);
PAINT ORANGE (-3925 3760);
WIRE 16 -1 (-3150 3750)(-3150 3700);
WIRE 16 -1 (-3150 3700)(-3000 3700);
WIRE 16 -1 (-3000 3500)(-3200 3500);
WIRE 16 -1 (-3000 3250)(-3200 3250);
WIRE 16 -1 (-3000 3200)(-3200 3200);
WIRE 16 -1 (-3000 3100)(-3200 3100);
WIRE 16 -1 (-3000 3400)(-3200 3400);
WIRE 16 -1 (-3000 3800)(-3400 3800);
WIRE 16 -1 (-3000 2750)(-3200 2750);
WIRE 16 -1 (-3000 2800)(-3200 2800);
WIRE 16 -1 (-3000 2850)(-3200 2850);
WIRE 16 -1 (-3000 2900)(-3200 2900);
WIRE 16 -1 (-3000 2950)(-3200 2950);
WIRE 16 -1 (-3000 3000)(-3200 3000);
WIRE 16 -1 (-3000 3050)(-3200 3050);
WIRE 16 -1 (-3000 3550)(-3200 3550);
WIRE 16 -1 (-3000 3600)(-3200 3600);
WIRE 16 -1 (-3000 3650)(-3200 3650);
WIRE 16 -1 (-3000 3350)(-3200 3350);
WIRE 16 -1 (-3000 3950)(-3200 3950);
WIRE 16 -1 (-3000 3900)(-3400 3900);
WIRE 16 -1 (-3000 3850)(-3200 3850);
WIRE 16 -1 (-3000 2500)(-3975 2500);
FORCEPROP 2 LAST SIG_NAME M_D_ALERT_N
J 0
(-3925 2510);
DISPLAY 0.617021 (-3925 2510);
PAINT ORANGE (-3925 2510);
WIRE 16 -1 (-1800 2000)(-2000 2000);
WIRE 16 -1 (-1800 2250)(-2000 2250);
WIRE 16 -1 (-1800 2200)(-2000 2200);
WIRE 16 -1 (-1800 2150)(-2000 2150);
WIRE 16 -1 (-1800 2100)(-2000 2100);
WIRE 16 -1 (-1800 2050)(-2000 2050);
WIRE 16 -1 (-1800 2300)(-2000 2300);
WIRE 16 -1 (-1800 2400)(-2000 2400);
WIRE 16 -1 (-1800 2450)(-2000 2450);
WIRE 16 -1 (-1800 2500)(-2000 2500);
WIRE 16 -1 (-1800 2550)(-2000 2550);
WIRE 16 -1 (-1800 2750)(-2000 2750);
WIRE 16 -1 (-1800 2600)(-2000 2600);
WIRE 16 -1 (-1800 2650)(-2000 2650);
WIRE 16 -1 (-1800 2700)(-2000 2700);
WIRE 16 -1 (-1800 2800)(-2000 2800);
WIRE 16 -1 (-1800 2850)(-2000 2850);
WIRE 16 -1 (-1800 2900)(-2000 2900);
WIRE 16 -1 (-1800 2950)(-2000 2950);
WIRE 16 -1 (-1800 3000)(-2000 3000);
WIRE 16 -1 (-1800 3050)(-2000 3050);
WIRE 16 -1 (-1800 3300)(-2000 3300);
WIRE 16 -1 (-1800 3100)(-2000 3100);
WIRE 16 -1 (-1800 3150)(-2000 3150);
WIRE 16 -1 (-1800 3200)(-2000 3200);
WIRE 16 -1 (-1800 3250)(-2000 3250);
WIRE 16 -1 (-1800 3350)(-2000 3350);
WIRE 16 -1 (-1800 3500)(-2000 3500);
WIRE 16 -1 (-1800 3550)(-2000 3550);
WIRE 16 -1 (-1800 3400)(-2000 3400);
WIRE 16 -1 (-1800 3450)(-2000 3450);
WIRE 16 -1 (-1800 3800)(-2000 3800);
WIRE 16 -1 (-1800 3750)(-2000 3750);
WIRE 16 -1 (-1800 3600)(-2000 3600);
WIRE 16 -1 (-1800 3650)(-2000 3650);
WIRE 16 -1 (-1800 3700)(-2000 3700);
WIRE 16 -1 (-1800 3900)(-2000 3900);
WIRE 16 -1 (-1800 3850)(-2000 3850);
WIRE 16 -1 (-1800 3950)(-2000 3950);
WIRE 16 -1 (-1800 4000)(-2000 4000);
WIRE 16 -1 (-1800 4050)(-2000 4050);
WIRE 16 -1 (-3000 5000)(-3200 5000);
WIRE 16 -1 (-3000 4400)(-3200 4400);
WIRE 16 -1 (-3000 4150)(-3200 4150);
WIRE 16 -1 (-3000 4550)(-3200 4550);
WIRE 16 -1 (-3000 4450)(-3200 4450);
WIRE 16 -1 (-3000 5150)(-3200 5150);
WIRE 16 -1 (-3000 4950)(-3200 4950);
WIRE 16 -1 (-3000 4300)(-3200 4300);
WIRE 16 -1 (-3000 4200)(-3200 4200);
WIRE 16 -1 (-3000 4100)(-3200 4100);
WIRE 16 -1 (-1800 4350)(-2000 4350);
WIRE 16 -1 (-1800 4100)(-2000 4100);
WIRE 16 -1 (-1800 4150)(-2000 4150);
WIRE 16 -1 (-1800 4200)(-2000 4200);
WIRE 16 -1 (-1800 4250)(-2000 4250);
WIRE 16 -1 (-1800 4300)(-2000 4300);
WIRE 16 -1 (-1800 4400)(-2000 4400);
WIRE 16 -1 (-1800 4450)(-2000 4450);
WIRE 16 -1 (-1800 4500)(-2000 4500);
WIRE 16 -1 (-1800 4550)(-2000 4550);
WIRE 16 -1 (-1800 4600)(-2000 4600);
WIRE 16 -1 (-1800 4650)(-2000 4650);
WIRE 16 -1 (-1800 4700)(-2000 4700);
WIRE 16 -1 (-1800 4850)(-2000 4850);
WIRE 16 -1 (-1800 4750)(-2000 4750);
WIRE 16 -1 (-1800 4800)(-2000 4800);
WIRE 16 -1 (-1800 5100)(-2000 5100);
WIRE 16 -1 (-1800 5050)(-2000 5050);
WIRE 16 -1 (-1800 4950)(-2000 4950);
WIRE 16 -1 (-1800 5000)(-2000 5000);
WIRE 16 -1 (-1800 5150)(-2000 5150);
WIRE 16 -1 (850 4050)(400 4050);
WIRE 16 -1 (600 4000)(400 4000);
WIRE 16 -1 (850 3950)(400 3950);
WIRE 16 -1 (600 3900)(400 3900);
WIRE 16 -1 (850 3850)(400 3850);
WIRE 16 -1 (600 3800)(400 3800);
WIRE 16 -1 (850 3750)(400 3750);
WIRE 16 -1 (600 3700)(400 3700);
WIRE 16 -1 (850 3650)(400 3650);
WIRE 16 -1 (600 3600)(400 3600);
WIRE 16 -1 (850 3550)(400 3550);
WIRE 16 -1 (600 3500)(400 3500);
WIRE 16 -1 (850 3450)(400 3450);
WIRE 16 -1 (600 4400)(400 4400);
WIRE 16 -1 (850 4350)(400 4350);
WIRE 16 -1 (600 4300)(400 4300);
WIRE 16 -1 (850 4250)(400 4250);
WIRE 16 -1 (600 4200)(400 4200);
WIRE 16 -1 (600 4100)(400 4100);
WIRE 16 -1 (600 5100)(400 5100);
WIRE 16 -1 (850 5050)(400 5050);
WIRE 16 -1 (600 5000)(400 5000);
WIRE 16 -1 (850 4950)(400 4950);
WIRE 16 -1 (600 4900)(400 4900);
WIRE 16 -1 (850 4850)(400 4850);
WIRE 16 -1 (600 4800)(400 4800);
WIRE 16 -1 (850 4750)(400 4750);
WIRE 16 -1 (850 4650)(400 4650);
WIRE 16 -1 (600 4600)(400 4600);
WIRE 16 -1 (850 4550)(400 4550);
WIRE 16 -1 (600 4500)(400 4500);
WIRE 16 -1 (850 4450)(400 4450);
WIRE 16 -1 (600 5200)(400 5200);
WIRE 16 -1 (850 5150)(400 5150);
DOT 1 (2500 2950);
DOT 1 (650 2800);
DOT 1 (-750 1650);
DOT 1 (-3300 2200);
DOT 1 (-3300 2250);
DOT 1 (1100 3200);
DOT 1 (-750 2650);
DOT 1 (-750 2500);
DOT 1 (-750 1150);
DOT 1 (-750 2700);
DOT 1 (-4650 2000);
DOT 1 (-750 1250);
DOT 1 (-750 1200);
DOT 1 (-750 1300);
DOT 1 (-750 1400);
DOT 1 (-750 1450);
DOT 1 (-750 1500);
DOT 1 (-750 1550);
DOT 1 (-750 1600);
DOT 1 (-750 1700);
DOT 1 (-750 1900);
DOT 1 (-750 1850);
DOT 1 (-750 1950);
DOT 1 (-750 2000);
DOT 1 (-750 2050);
DOT 1 (-750 2100);
DOT 1 (-750 2150);
DOT 1 (-750 2200);
DOT 1 (-750 2250);
DOT 1 (-750 2300);
DOT 1 (-750 2350);
DOT 1 (1100 1300);
DOT 1 (1100 1400);
DOT 1 (1100 1350);
DOT 1 (1100 1450);
DOT 1 (1100 1500);
DOT 1 (1100 1550);
DOT 1 (1100 1600);
DOT 1 (1100 1650);
DOT 1 (1100 1700);
DOT 1 (1100 1800);
DOT 1 (1100 1750);
DOT 1 (1100 1850);
DOT 1 (1100 1900);
DOT 1 (1100 1950);
DOT 1 (1100 2000);
DOT 1 (1100 2050);
DOT 1 (1100 2100);
DOT 1 (1100 2150);
DOT 1 (1100 2200);
DOT 1 (1100 2300);
DOT 1 (1100 2250);
DOT 1 (1100 2350);
DOT 1 (1100 2400);
DOT 1 (1100 2450);
DOT 1 (1100 2550);
DOT 1 (1100 2600);
DOT 1 (1100 2500);
DOT 1 (1100 2700);
DOT 1 (1100 2650);
DOT 1 (1100 2750);
DOT 1 (1100 2800);
DOT 1 (1100 2850);
DOT 1 (1100 2900);
DOT 1 (1100 3050);
DOT 1 (1100 3100);
DOT 1 (1100 3150);
DOT 1 (1100 3250);
DOT 1 (1100 3300);
DOT 1 (1100 3350);
DOT 1 (1100 3450);
DOT 1 (1100 3400);
DOT 1 (2500 1300);
DOT 1 (2500 1350);
DOT 1 (2500 1400);
DOT 1 (2500 1450);
DOT 1 (2500 1500);
DOT 1 (2500 1550);
DOT 1 (2500 1600);
DOT 1 (2500 1650);
DOT 1 (2500 1700);
DOT 1 (2500 1800);
DOT 1 (2500 1850);
DOT 1 (2500 1900);
DOT 1 (2500 1950);
DOT 1 (2500 2000);
DOT 1 (2500 2050);
DOT 1 (2500 2100);
DOT 1 (2500 2150);
DOT 1 (2500 2200);
DOT 1 (2500 2250);
DOT 1 (2500 2300);
DOT 1 (2500 2350);
DOT 1 (2500 2400);
DOT 1 (2500 2450);
DOT 1 (2500 2500);
DOT 1 (2500 2550);
DOT 1 (2500 2600);
DOT 1 (2500 2650);
DOT 1 (2500 2700);
DOT 1 (2500 2750);
DOT 1 (2500 2800);
DOT 1 (2500 2850);
DOT 1 (2500 2900);
DOT 1 (2500 3000);
DOT 1 (2500 3050);
DOT 1 (2500 3100);
DOT 1 (2500 3150);
DOT 1 (2500 3200);
DOT 1 (2500 3250);
DOT 1 (2500 3300);
DOT 1 (2500 3350);
DOT 1 (2500 3400);
DOT 1 (2500 3450);
DOT 1 (1100 3500);
DOT 1 (2500 3500);
DOT 1 (1100 3550);
DOT 1 (2500 3550);
DOT 1 (2500 1750);
DOT 1 (-750 1350);
DOT 1 (-750 1800);
DOT 1 (-750 1750);
DOT 1 (-750 2800);
DOT 1 (-750 2750);
DOT 1 (1100 3000);
DOT 1 (1100 2950);
FORCENOTE
PVDDQ (SINGLE SIDE) CAP: 10UF X1, 22UF X50
(-4050 1225) 0;
DISPLAY LEFT (-4050 1225);
DISPLAY 1.021277 (-4050 1225);
PAINT PURPLE (-4050 1225);
FORCENOTE
PVDDQ (DOUBLE SIDE) CAP: 100UF X8, 47UF X41
(-4050 1175) 0;
DISPLAY LEFT (-4050 1175);
DISPLAY 1.021277 (-4050 1175);
PAINT PURPLE (-4050 1175);
FORCENOTE
PVTT CAP: 100UF X2, 47UF X1
(-4050 1275) 0;
DISPLAY LEFT (-4050 1275);
DISPLAY 1.021277 (-4050 1275);
PAINT PURPLE (-4050 1275);
FORCENOTE
PVPP CAP: 10UF X12
(-4050 1325) 0;
DISPLAY LEFT (-4050 1325);
DISPLAY 1.021277 (-4050 1325);
PAINT PURPLE (-4050 1325);
FORCENOTE
CAP BETWEEN DIMM
(-4050 1400) 0;
DISPLAY LEFT (-4050 1400);
DISPLAY 1.276596 (-4050 1400);
PAINT PURPLE (-4050 1400);
FORCENOTE
SMBUS ADDR: 0XA0
(-5308 693) 0;
DISPLAY LEFT (-5308 693);
DISPLAY 1.595745 (-5308 693);
PAINT PURPLE (-5308 693);
FORCENOTE
PLACE CAP NEAR DIMM CONNECTOR
(-5288 852) 0;
DISPLAY LEFT (-5288 852);
DISPLAY 1.595745 (-5288 852);
PAINT PURPLE (-5288 852);
QUIT
